# Altium SchDoc records: POWER.SchDoc
|HEADER=Protel for Windows - Schematic Capture Binary File Version 5.0|Weight=1766|MinorVersion=2
|RECORD=31|FontIdCount=7|Size1=10|FontName1=Times New Roman|Size2=12|FontName2=Arial|Size3=14|FontName3=Arial|Size4=7|FontName4=Arial|Size5=8|FontName5=Arial|Size6=10|FontName6=Arial|Size7=12|Underline7=T|FontName7=Arial|UseMBCS=T|IsBOC=T|HotSpotGridOn=T|HotSpotGridSize=1|SheetStyle=12|SystemFont=6|BorderOn=T|SheetNumberSpaceSize=12|AreaColor=16317695|SnapGridOn=T|SnapGridSize=1|VisibleGridOn=T|VisibleGridSize=10|CustomX=2338|CustomX_Frac=58268|CustomY=1653|CustomY_Frac=54331|CustomXZones=8|CustomYZones=6|CustomMarginWidth=19|CustomMarginWidth_Frac=80000|ShowTemplateGraphics=T|TemplateFileName=C:\Users\<user>\Documents\Altium\AD20\Templates\Timecard.SchDot|Display_Unit=0
|RECORD=39|IsNotAccesible=T|OwnerPartId=-1|FileName=C:\Users\<user>\Documents\Altium\AD20\Templates\Timecard.SchDot
|RECORD=4|OwnerIndex=1|OwnerPartId=-1|Location.X=1594|Location.Y=39|Color=8388608|FontID=7|Text=timingcard.com|URL=http://timingcard.com
|RECORD=6|OwnerIndex=1|IndexInSheet=1|OwnerPartId=-1|LocationCount=2|X1=1680|Y1=35|X2=1576|Y2=35
|RECORD=4|OwnerIndex=1|IndexInSheet=2|OwnerPartId=-1|Location.X=1614|Location.X_Frac=42446|Location.Y=19|Location.Y_Frac=96838|FontID=2|Text==SheetNumber
|RECORD=4|OwnerIndex=1|IndexInSheet=3|OwnerPartId=-1|Location.X=1581|Location.X_Frac=42446|Location.Y=29|Location.Y_Frac=96838|Justification=3|FontID=5|Text=SHEET
|RECORD=4|OwnerIndex=1|IndexInSheet=4|OwnerPartId=-1|Location.X=1639|Location.X_Frac=42446|Location.Y=29|Location.Y_Frac=96838|Justification=3|FontID=5|Text=OF
|RECORD=6|OwnerIndex=1|IndexInSheet=5|OwnerPartId=-1|LineWidth=1|LocationCount=2|X1=1679|X1_Frac=42446|Y1=105|Y1_Frac=96838|X2=1576|Y2=106
|RECORD=4|OwnerIndex=1|IndexInSheet=6|OwnerPartId=-1|Location.X=1658|Location.Y=20|FontID=2|Text==SheetTotal
|RECORD=30|OwnerIndex=1|IndexInSheet=7|OwnerPartId=-1|Location.X=1578|Location.Y=53|Corner.X=1673|Corner.X_Frac=88801|Corner.Y=103|KeepAspect=T|FileName=C:\Users\<user>\Desktop\Timecard Logo\TIMECARD.jpg
|RECORD=6|OwnerIndex=1|IndexInSheet=8|OwnerPartId=-1|LineWidth=1|LocationCount=2|X1=1576|X1_Frac=3162|Y1=105|Y1_Frac=42446|X2=1576|Y2=20
|RECORD=6|OwnerIndex=1|IndexInSheet=9|OwnerPartId=-1|LocationCount=2|X1=1680|Y1=51|X2=1576|Y2=51
|RECORD=41|IndexInSheet=1|OwnerPartId=-1|Color=8388608|FontID=1|IsHidden=T|Text=*|Name=CurrentTime|ReadOnlyState=1
|RECORD=41|IndexInSheet=2|OwnerPartId=-1|Color=8388608|FontID=1|IsHidden=T|Text=*|Name=CurrentDate|ReadOnlyState=1
|RECORD=41|IndexInSheet=3|OwnerPartId=-1|Color=8388608|FontID=1|IsHidden=T|Text=*|Name=Time|ReadOnlyState=1
|RECORD=41|IndexInSheet=4|OwnerPartId=-1|Color=8388608|FontID=1|IsHidden=T|Text=*|Name=Date|ReadOnlyState=1
|RECORD=41|IndexInSheet=5|OwnerPartId=-1|Color=8388608|FontID=1|IsHidden=T|Text=*|Name=DocumentFullPathAndName|ReadOnlyState=1
|RECORD=41|IndexInSheet=6|OwnerPartId=-1|Color=8388608|FontID=1|IsHidden=T|Text=*|Name=DocumentName|ReadOnlyState=1
|RECORD=41|IndexInSheet=7|OwnerPartId=-1|Color=8388608|FontID=1|IsHidden=T|Text=*|Name=ModifiedDate|ReadOnlyState=1
|RECORD=41|IndexInSheet=8|OwnerPartId=-1|Color=8388608|FontID=1|IsHidden=T|Text=*|Name=ApprovedBy|ReadOnlyState=1
|RECORD=41|IndexInSheet=9|OwnerPartId=-1|Color=8388608|FontID=1|IsHidden=T|Text=*|Name=CheckedBy|ReadOnlyState=1
|RECORD=41|IndexInSheet=10|OwnerPartId=-1|Color=8388608|FontID=1|IsHidden=T|Text=<name>|Name=Author|ReadOnlyState=1
|RECORD=41|IndexInSheet=11|OwnerPartId=-1|Color=8388608|FontID=1|IsHidden=T|Text=*|Name=CompanyName|ReadOnlyState=1
|RECORD=41|IndexInSheet=12|OwnerPartId=-1|Color=8388608|FontID=1|IsHidden=T|Text=*|Name=DrawnBy|ReadOnlyState=1
|RECORD=41|IndexInSheet=13|OwnerPartId=-1|Color=8388608|FontID=1|IsHidden=T|Text=*|Name=Engineer|ReadOnlyState=1
|RECORD=41|IndexInSheet=14|OwnerPartId=-1|Color=8388608|FontID=1|IsHidden=T|Text=*|Name=Organization|ReadOnlyState=1
|RECORD=41|IndexInSheet=15|OwnerPartId=-1|Color=8388608|FontID=1|IsHidden=T|Text=*|Name=Address1|ReadOnlyState=1
|RECORD=41|IndexInSheet=16|OwnerPartId=-1|Color=8388608|FontID=1|IsHidden=T|Text=*|Name=Address2|ReadOnlyState=1
|RECORD=41|IndexInSheet=17|OwnerPartId=-1|Color=8388608|FontID=1|IsHidden=T|Text=*|Name=Address3|ReadOnlyState=1
|RECORD=41|IndexInSheet=18|OwnerPartId=-1|Color=8388608|FontID=1|IsHidden=T|Text=*|Name=Address4|ReadOnlyState=1
|RECORD=41|IndexInSheet=19|OwnerPartId=-1|Color=8388608|FontID=1|IsHidden=T|Text=Grandmaster Power Supplies|Name=Title|ReadOnlyState=1
|RECORD=41|IndexInSheet=20|OwnerPartId=-1|Color=8388608|FontID=1|IsHidden=T|Text=*|Name=DocumentNumber|ReadOnlyState=1
|RECORD=41|IndexInSheet=21|OwnerPartId=-1|Color=8388608|FontID=1|IsHidden=T|Text=A|Name=Revision|ReadOnlyState=1
|RECORD=41|IndexInSheet=22|OwnerPartId=-1|Color=8388608|FontID=1|IsHidden=T|Text=2|Name=SheetNumber|ReadOnlyState=1
|RECORD=41|IndexInSheet=23|OwnerPartId=-1|Color=8388608|FontID=1|IsHidden=T|Text=7|Name=SheetTotal|ReadOnlyState=1
|RECORD=41|IndexInSheet=24|OwnerPartId=-1|Color=8388608|FontID=1|IsHidden=T|Text=*|Name=Rule|ReadOnlyState=1
|RECORD=41|IndexInSheet=25|OwnerPartId=-1|Color=8388608|FontID=1|IsHidden=T|Text=*|Name=ImagePath|ReadOnlyState=1
|RECORD=41|IndexInSheet=26|OwnerPartId=-1|Color=8388608|FontID=1|IsHidden=T|Text=*|Name=ProjectName|ReadOnlyState=1
|RECORD=41|IndexInSheet=27|OwnerPartId=-1|Color=8388608|FontID=1|IsHidden=T|Text=*|Name=Application_BuildNumber|ReadOnlyState=1
|RECORD=41|IndexInSheet=28|OwnerPartId=-1|Location.X=21474|Location.X_Frac=83647|Location.Y=21464|Location.Y_Frac=83647|Color=8388608|FontID=1|IsHidden=T|Text=01910|Name=Customer
|RECORD=41|IndexInSheet=29|OwnerPartId=-1|Location.X=1000|Location.Y=10|Color=8388608|FontID=1|IsHidden=T|Text=*|Name=DocStatus
|RECORD=1|LibReference=screw_0|ComponentDescription=FH140 Screw,Diameter 2.9mm|PartCount=2|DisplayModeCount=1|IndexInSheet=30|OwnerPartId=-1|Location.X=1050|Location.Y=900|CurrentPartId=1|LibraryPath=*|SourceLibraryName=AX7103_AD_Schematics.SCHLIB|TargetFileName=*|AreaColor=11599871|Color=128|PartIDLocked=T|DesignItemId=screw_0|AllPinCount=1
|RECORD=8|OwnerIndex=41|IsNotAccesible=T|OwnerPartId=1|Location.X=1075|Location.Y=875|Radius=25|SecondaryRadius=25|LineWidth=1|Color=16711680|AreaColor=12632256
|RECORD=8|OwnerIndex=41|IsNotAccesible=T|IndexInSheet=1|OwnerPartId=1|Location.X=1075|Location.Y=875|Radius=15|SecondaryRadius=15|LineWidth=1|Color=16711680|AreaColor=12632256
|RECORD=2|OwnerIndex=41|OwnerPartId=1|FormalType=1|Electrical=4|PinConglomerate=59|PinLength=10|Location.X=1070|Location.Y=850|Name=1|Designator=1|SwapIDPart=Ž&Ž||PinPropagationDelay=0.000000E+000
|RECORD=41|OwnerIndex=41|IndexInSheet=3|OwnerPartId=1|Location.X=-40|Location.Y=-220|Color=8388608|FontID=1|IsHidden=T|Text=454|Name=Part Number|NotAutoPosition=T
|RECORD=41|OwnerIndex=41|IndexInSheet=4|OwnerPartId=1|Location.X=-40|Location.Y=-220|Color=8388608|FontID=1|IsHidden=T|Text=NA|Name=Manufacturer|NotAutoPosition=T
|RECORD=41|OwnerIndex=41|IndexInSheet=5|OwnerPartId=1|Location.X=-40|Location.Y=-220|Color=8388608|FontID=1|IsHidden=T|Text=NA|Name=Vendor P/N|NotAutoPosition=T
|RECORD=41|OwnerIndex=41|IndexInSheet=6|OwnerPartId=1|Location.X=-40|Location.Y=-220|Color=8388608|FontID=1|IsHidden=T|Text=SMT|Name=Part Type|NotAutoPosition=T
|RECORD=34|OwnerIndex=41|IndexInSheet=-1|OwnerPartId=1|Location.X=1057|Location.Y=907|Color=8388608|FontID=4|Text=S1|Name=Designator|ReadOnlyState=1|OverrideNotAutoPosition=T
|RECORD=41|OwnerIndex=41|IndexInSheet=-1|OwnerPartId=-1|Location.X=1058|Location.Y=839|Color=8388608|FontID=4|Text=Screw_2.9|Name=Comment|NotAutoPosition=T
|RECORD=44|OwnerIndex=41
|RECORD=45|OwnerIndex=52|IndexInSheet=-1|ModelName=MH_250H125|ModelType=PCBLIB|DatafileCount=1|ModelDatafileEntity0=MH_250H125|ModelDatafileKind0=PCBLib|IsCurrent=T
|RECORD=46|OwnerIndex=53
|RECORD=48|OwnerIndex=53
|RECORD=1|LibReference=screw_0|ComponentDescription=FH140 Screw,Diameter 2.9mm|PartCount=2|DisplayModeCount=1|IndexInSheet=31|OwnerPartId=-1|Location.X=1140|Location.Y=900|CurrentPartId=1|LibraryPath=*|SourceLibraryName=AX7103_AD_Schematics.SCHLIB|TargetFileName=*|AreaColor=11599871|Color=128|PartIDLocked=T|DesignItemId=screw_0|AllPinCount=1
|RECORD=8|OwnerIndex=56|IsNotAccesible=T|OwnerPartId=1|Location.X=1165|Location.Y=875|Radius=25|SecondaryRadius=25|LineWidth=1|Color=16711680|AreaColor=12632256
|RECORD=8|OwnerIndex=56|IsNotAccesible=T|IndexInSheet=1|OwnerPartId=1|Location.X=1165|Location.Y=875|Radius=15|SecondaryRadius=15|LineWidth=1|Color=16711680|AreaColor=12632256
|RECORD=2|OwnerIndex=56|OwnerPartId=1|FormalType=1|Electrical=4|PinConglomerate=59|PinLength=10|Location.X=1160|Location.Y=850|Name=1|Designator=1|SwapIDPart=Ž&Ž||PinPropagationDelay=0.000000E+000
|RECORD=41|OwnerIndex=56|IndexInSheet=3|OwnerPartId=1|Location.X=50|Location.Y=-220|Color=8388608|FontID=1|IsHidden=T|Text=454|Name=Part Number|NotAutoPosition=T
|RECORD=41|OwnerIndex=56|IndexInSheet=4|OwnerPartId=1|Location.X=50|Location.Y=-220|Color=8388608|FontID=1|IsHidden=T|Text=NA|Name=Manufacturer|NotAutoPosition=T
|RECORD=41|OwnerIndex=56|IndexInSheet=5|OwnerPartId=1|Location.X=50|Location.Y=-220|Color=8388608|FontID=1|IsHidden=T|Text=NA|Name=Vendor P/N|NotAutoPosition=T
|RECORD=41|OwnerIndex=56|IndexInSheet=6|OwnerPartId=1|Location.X=50|Location.Y=-220|Color=8388608|FontID=1|IsHidden=T|Text=SMT|Name=Part Type|NotAutoPosition=T
|RECORD=34|OwnerIndex=56|IndexInSheet=-1|OwnerPartId=1|Location.X=1147|Location.Y=907|Color=8388608|FontID=4|Text=S2|Name=Designator|ReadOnlyState=1|OverrideNotAutoPosition=T
|RECORD=41|OwnerIndex=56|IndexInSheet=-1|OwnerPartId=-1|Location.X=1148|Location.Y=839|Color=8388608|FontID=4|Text=Screw_2.9|Name=Comment|NotAutoPosition=T
|RECORD=44|OwnerIndex=56
|RECORD=45|OwnerIndex=67|IndexInSheet=-1|ModelName=MH_250H125|ModelType=PCBLIB|DatafileCount=1|ModelDatafileEntity0=MH_250H125|ModelDatafileKind0=PCBLib|IsCurrent=T
|RECORD=46|OwnerIndex=68
|RECORD=48|OwnerIndex=68
|RECORD=1|LibReference=screw_0|ComponentDescription=FH140 Screw,Diameter 2.9mm|PartCount=2|DisplayModeCount=1|IndexInSheet=32|OwnerPartId=-1|Location.X=1230|Location.Y=900|CurrentPartId=1|LibraryPath=*|SourceLibraryName=AX7103_AD_Schematics.SCHLIB|TargetFileName=*|AreaColor=11599871|Color=128|PartIDLocked=T|DesignItemId=screw_0|AllPinCount=1
|RECORD=8|OwnerIndex=71|IsNotAccesible=T|OwnerPartId=1|Location.X=1255|Location.Y=875|Radius=25|SecondaryRadius=25|LineWidth=1|Color=16711680|AreaColor=12632256
|RECORD=8|OwnerIndex=71|IsNotAccesible=T|IndexInSheet=1|OwnerPartId=1|Location.X=1255|Location.Y=875|Radius=15|SecondaryRadius=15|LineWidth=1|Color=16711680|AreaColor=12632256
|RECORD=2|OwnerIndex=71|OwnerPartId=1|FormalType=1|Electrical=4|PinConglomerate=59|PinLength=10|Location.X=1250|Location.Y=850|Name=1|Designator=1|SwapIDPart=Ž&Ž||PinPropagationDelay=0.000000E+000
|RECORD=41|OwnerIndex=71|IndexInSheet=3|OwnerPartId=1|Location.X=140|Location.Y=-220|Color=8388608|FontID=1|IsHidden=T|Text=454|Name=Part Number|NotAutoPosition=T
|RECORD=41|OwnerIndex=71|IndexInSheet=4|OwnerPartId=1|Location.X=140|Location.Y=-220|Color=8388608|FontID=1|IsHidden=T|Text=NA|Name=Manufacturer|NotAutoPosition=T
|RECORD=41|OwnerIndex=71|IndexInSheet=5|OwnerPartId=1|Location.X=140|Location.Y=-220|Color=8388608|FontID=1|IsHidden=T|Text=NA|Name=Vendor P/N|NotAutoPosition=T
|RECORD=41|OwnerIndex=71|IndexInSheet=6|OwnerPartId=1|Location.X=140|Location.Y=-220|Color=8388608|FontID=1|IsHidden=T|Text=SMT|Name=Part Type|NotAutoPosition=T
|RECORD=34|OwnerIndex=71|IndexInSheet=-1|OwnerPartId=1|Location.X=1237|Location.Y=907|Color=8388608|FontID=4|Text=S3|Name=Designator|ReadOnlyState=1|OverrideNotAutoPosition=T
|RECORD=41|OwnerIndex=71|IndexInSheet=-1|OwnerPartId=-1|Location.X=1238|Location.Y=839|Color=8388608|FontID=4|Text=Screw_2.9|Name=Comment|NotAutoPosition=T
|RECORD=44|OwnerIndex=71
|RECORD=45|OwnerIndex=82|IndexInSheet=-1|ModelName=MH_250H125|ModelType=PCBLIB|DatafileCount=1|ModelDatafileEntity0=MH_250H125|ModelDatafileKind0=PCBLib|IsCurrent=T
|RECORD=46|OwnerIndex=83
|RECORD=48|OwnerIndex=83
|RECORD=1|LibReference=screw_0|ComponentDescription=FH140 Screw,Diameter 2.9mm|PartCount=2|DisplayModeCount=1|IndexInSheet=33|OwnerPartId=-1|Location.X=1310|Location.Y=900|CurrentPartId=1|LibraryPath=*|SourceLibraryName=AX7103_AD_Schematics.SCHLIB|TargetFileName=*|AreaColor=11599871|Color=128|PartIDLocked=T|DesignItemId=screw_0|AllPinCount=1
|RECORD=8|OwnerIndex=86|IsNotAccesible=T|OwnerPartId=1|Location.X=1335|Location.Y=875|Radius=25|SecondaryRadius=25|LineWidth=1|Color=16711680|AreaColor=12632256
|RECORD=8|OwnerIndex=86|IsNotAccesible=T|IndexInSheet=1|OwnerPartId=1|Location.X=1335|Location.Y=875|Radius=15|SecondaryRadius=15|LineWidth=1|Color=16711680|AreaColor=12632256
|RECORD=2|OwnerIndex=86|OwnerPartId=1|FormalType=1|Electrical=4|PinConglomerate=59|PinLength=10|Location.X=1330|Location.Y=850|Name=1|Designator=1|SwapIDPart=Ž&Ž||PinPropagationDelay=0.000000E+000
|RECORD=41|OwnerIndex=86|IndexInSheet=3|OwnerPartId=1|Location.X=220|Location.Y=-220|Color=8388608|FontID=1|IsHidden=T|Text=454|Name=Part Number|NotAutoPosition=T
|RECORD=41|OwnerIndex=86|IndexInSheet=4|OwnerPartId=1|Location.X=220|Location.Y=-220|Color=8388608|FontID=1|IsHidden=T|Text=NA|Name=Manufacturer|NotAutoPosition=T
|RECORD=41|OwnerIndex=86|IndexInSheet=5|OwnerPartId=1|Location.X=220|Location.Y=-220|Color=8388608|FontID=1|IsHidden=T|Text=NA|Name=Vendor P/N|NotAutoPosition=T
|RECORD=41|OwnerIndex=86|IndexInSheet=6|OwnerPartId=1|Location.X=220|Location.Y=-220|Color=8388608|FontID=1|IsHidden=T|Text=SMT|Name=Part Type|NotAutoPosition=T
|RECORD=34|OwnerIndex=86|IndexInSheet=-1|OwnerPartId=1|Location.X=1317|Location.Y=907|Color=8388608|FontID=4|Text=S4|Name=Designator|ReadOnlyState=1|OverrideNotAutoPosition=T
|RECORD=41|OwnerIndex=86|IndexInSheet=-1|OwnerPartId=-1|Location.X=1318|Location.Y=839|Color=8388608|FontID=4|Text=Screw_2.9|Name=Comment|NotAutoPosition=T
|RECORD=44|OwnerIndex=86
|RECORD=45|OwnerIndex=97|IndexInSheet=-1|ModelName=MH_250H125|ModelType=PCBLIB|DatafileCount=1|ModelDatafileEntity0=MH_250H125|ModelDatafileKind0=PCBLib|IsCurrent=T
|RECORD=46|OwnerIndex=98
|RECORD=48|OwnerIndex=98
|RECORD=17|IndexInSheet=34|OwnerPartId=-1|ShowNetName=T|Location.X=680|Location.Y=990|Orientation=1|Color=128|FontID=1|Text=+12V
|RECORD=17|IndexInSheet=35|OwnerPartId=-1|Style=4|ShowNetName=T|Location.X=210|Location.Y=900|Orientation=3|Color=128|FontID=1|Text=GND
|RECORD=17|IndexInSheet=36|OwnerPartId=-1|Style=4|ShowNetName=T|Location.X=210|Location.Y=760|Orientation=3|Color=128|FontID=1|Text=GND
|RECORD=17|IndexInSheet=37|OwnerPartId=-1|Style=4|ShowNetName=T|Location.X=680|Location.Y=880|Orientation=3|Color=128|FontID=1|Text=GND
|RECORD=17|IndexInSheet=38|OwnerPartId=-1|ShowNetName=T|Location.X=450|Location.Y=540|Orientation=1|Color=128|FontID=1|Text=+5.0V
|RECORD=17|IndexInSheet=39|OwnerPartId=-1|ShowNetName=T|Location.X=1620|Location.Y=440|Orientation=1|Color=128|FontID=1|Text=+3.3V
|RECORD=17|IndexInSheet=40|OwnerPartId=-1|Style=4|ShowNetName=T|Location.X=100|Location.Y=320|Orientation=3|Color=128|FontID=1|Text=GND
|RECORD=17|IndexInSheet=41|OwnerPartId=-1|Style=4|ShowNetName=T|Location.X=380|Location.Y=320|Orientation=3|Color=128|FontID=1|Text=GND
|RECORD=17|IndexInSheet=42|OwnerPartId=-1|Style=4|ShowNetName=T|Location.X=1620|Location.Y=280|Orientation=3|Color=128|FontID=1|Text=GND
|RECORD=17|IndexInSheet=43|OwnerPartId=-1|Style=4|ShowNetName=T|Location.X=820|Location.Y=280|Orientation=3|Color=128|FontID=1|Text=GND
|RECORD=17|IndexInSheet=44|OwnerPartId=-1|Style=4|ShowNetName=T|Location.X=1100|Location.Y=280|Orientation=3|Color=128|FontID=1|Text=GND
|RECORD=17|IndexInSheet=45|OwnerPartId=-1|ShowNetName=T|Location.X=1260|Location.Y=550|Orientation=1|Color=128|FontID=1|Text=+3.3V
|RECORD=17|IndexInSheet=46|OwnerPartId=-1|ShowNetName=T|Location.X=50|Location.Y=550|Orientation=1|Color=128|FontID=1|Text=+12V
|RECORD=17|IndexInSheet=47|OwnerPartId=-1|ShowNetName=T|Location.X=820|Location.Y=560|Orientation=1|Color=128|FontID=1|Text=+12V
|RECORD=1|LibReference=PJ-002A|ComponentDescription=CONN, JACK, PJ-002A, 2.1X5.5MM, 24V 2.5A, R/A TH, SPST-NC|PartCount=2|DisplayModeCount=1|IndexInSheet=48|OwnerPartId=-1|Location.X=170|Location.Y=940|CurrentPartId=1|LibraryPath=*|SourceLibraryName=Connectors.IntLib|TargetFileName=*|AreaColor=11599871|Color=128|PartIDLocked=T|DesignItemId=PJ-002A|AllPinCount=3
|RECORD=41|OwnerIndex=115|OwnerPartId=-1|Location.X=142|Location.X_Frac=50000|Location.Y=958|Location.Y_Frac=50000|Color=8388608|FontID=2|IsHidden=T|Text=CONN, JACK|Name=CATEGORY
|RECORD=41|OwnerIndex=115|IndexInSheet=1|OwnerPartId=-1|Location.X=142|Location.X_Frac=50000|Location.Y=958|Location.Y_Frac=50000|Color=8388608|FontID=2|IsHidden=T|Text=CONN, JACK, PJ-002A, 2.1X5.5MM, 24V 2.5A, R/A TH, SPST-NC|Name=DESC
|RECORD=41|OwnerIndex=115|IndexInSheet=2|OwnerPartId=-1|Location.X=142|Location.X_Frac=50000|Location.Y=958|Location.Y_Frac=50000|Color=8388608|FontID=2|IsHidden=T|Text=85C|Name=MAXTEMP
|RECORD=41|OwnerIndex=115|IndexInSheet=3|OwnerPartId=-1|Location.X=142|Location.X_Frac=50000|Location.Y=958|Location.Y_Frac=50000|Color=8388608|FontID=2|IsHidden=T|Text=CUI DEVICES|Name=MFG NAME
|RECORD=41|OwnerIndex=115|IndexInSheet=4|OwnerPartId=-1|Location.X=142|Location.X_Frac=50000|Location.Y=958|Location.Y_Frac=50000|Color=8388608|FontID=2|IsHidden=T|Text=PJ-002A|Name=MFG PART NUM
|RECORD=41|OwnerIndex=115|IndexInSheet=5|OwnerPartId=-1|Location.X=142|Location.X_Frac=50000|Location.Y=958|Location.Y_Frac=50000|Color=8388608|FontID=2|IsHidden=T|Text=-25C|Name=MINTEMP
|RECORD=41|OwnerIndex=115|IndexInSheet=6|OwnerPartId=-1|Location.X=142|Location.X_Frac=50000|Location.Y=958|Location.Y_Frac=50000|Color=8388608|FontID=2|IsHidden=T|Name=MODIFY DATE
|RECORD=41|OwnerIndex=115|IndexInSheet=7|OwnerPartId=-1|Location.X=142|Location.X_Frac=50000|Location.Y=958|Location.Y_Frac=50000|Color=8388608|FontID=2|IsHidden=T|Text=SPST-NC|Name=OTHER
|RECORD=41|OwnerIndex=115|IndexInSheet=8|OwnerPartId=-1|Location.X=142|Location.X_Frac=50000|Location.Y=958|Location.Y_Frac=50000|Color=8388608|FontID=2|IsHidden=T|Name=SHEETPART
|RECORD=41|OwnerIndex=115|IndexInSheet=9|OwnerPartId=-1|Location.X=142|Location.X_Frac=50000|Location.Y=958|Location.Y_Frac=50000|Color=8388608|FontID=2|IsHidden=T|Name=SUB
|RECORD=41|OwnerIndex=115|IndexInSheet=10|OwnerPartId=-1|Location.X=142|Location.X_Frac=50000|Location.Y=958|Location.Y_Frac=50000|Color=8388608|FontID=2|IsHidden=T|Text=Digi-Key|Name=Supplier 1|ReadOnlyState=3
|RECORD=41|OwnerIndex=115|IndexInSheet=11|OwnerPartId=-1|Location.X=142|Location.X_Frac=50000|Location.Y=958|Location.Y_Frac=50000|Color=8388608|FontID=2|IsHidden=T|Text=CP-002A-ND|Name=Supplier Part Number 1|ReadOnlyState=3
|RECORD=41|OwnerIndex=115|IndexInSheet=12|OwnerPartId=-1|Location.X=139|Location.X_Frac=99535|Location.Y=974|Location.Y_Frac=311|Color=8388608|FontID=1|IsHidden=T|Text=<VALENTIUM>|Name=VALENTIUM PART NUM
|RECORD=41|OwnerIndex=115|IndexInSheet=13|OwnerPartId=-1|Location.X=142|Location.X_Frac=50000|Location.Y=915|Color=8388608|FontID=2|Text=2.1X5.5MM|Name=P1
|RECORD=41|OwnerIndex=115|IndexInSheet=14|OwnerPartId=-1|Location.X=142|Location.X_Frac=50000|Location.Y=903|Color=8388608|FontID=2|Text=24V|Name=P2
|RECORD=41|OwnerIndex=115|IndexInSheet=15|OwnerPartId=-1|Location.X=142|Location.X_Frac=50000|Location.Y=891|Color=8388608|FontID=2|Text=2.5A|Name=P3
|RECORD=41|OwnerIndex=115|IndexInSheet=16|OwnerPartId=-1|Location.X=142|Location.X_Frac=50000|Location.Y=879|Color=8388608|FontID=2|Text=R/A TH|Name=SIZE
|RECORD=41|OwnerIndex=115|IndexInSheet=17|OwnerPartId=-1|Location.X=142|Location.X_Frac=50000|Location.Y=867|Color=8388608|FontID=2|Text=PJ-002A|Name=Value
|RECORD=7|OwnerIndex=115|IsNotAccesible=T|IndexInSheet=18|OwnerPartId=1|LineWidth=1|Color=16711680|AreaColor=16711680|IsSolid=T|LocationCount=3|X1=170|Y1=930|X2=168|Y2=935|X3=172|Y3=935
|RECORD=6|OwnerIndex=115|IsNotAccesible=T|IndexInSheet=19|OwnerPartId=1|LineWidth=1|LocationCount=2|X1=170|Y1=940|X2=170|Y2=930
|RECORD=6|OwnerIndex=115|IsNotAccesible=T|IndexInSheet=20|OwnerPartId=1|LineWidth=1|LocationCount=2|X1=155|Y1=935|X2=152|X2_Frac=50000|Y2=930
|RECORD=6|OwnerIndex=115|IsNotAccesible=T|IndexInSheet=21|OwnerPartId=1|LineWidth=1|LocationCount=2|X1=157|X1_Frac=50000|Y1=930|X2=155|Y2=935
|RECORD=6|OwnerIndex=115|IsNotAccesible=T|IndexInSheet=22|OwnerPartId=1|LineWidth=1|LocationCount=2|X1=170|Y1=930|X2=157|X2_Frac=50000|Y2=930
|RECORD=6|OwnerIndex=115|IsNotAccesible=T|IndexInSheet=23|OwnerPartId=1|LineWidth=1|LocationCount=2|X1=165|Y1=957|Y1_Frac=50000|X2=165|Y2=955
|RECORD=6|OwnerIndex=115|IsNotAccesible=T|IndexInSheet=24|OwnerPartId=1|LineWidth=1|LocationCount=2|X1=170|Y1=957|Y1_Frac=50000|X2=165|Y2=957|Y2_Frac=50000
|RECORD=6|OwnerIndex=115|IsNotAccesible=T|IndexInSheet=25|OwnerPartId=1|LineWidth=1|LocationCount=2|X1=170|Y1=942|Y1_Frac=50000|X2=170|Y2=957|Y2_Frac=50000
|RECORD=6|OwnerIndex=115|IsNotAccesible=T|IndexInSheet=26|OwnerPartId=1|LineWidth=1|LocationCount=2|X1=165|Y1=942|Y1_Frac=50000|X2=170|Y2=942|Y2_Frac=50000
|RECORD=6|OwnerIndex=115|IsNotAccesible=T|IndexInSheet=27|OwnerPartId=1|LineWidth=1|LocationCount=2|X1=165|Y1=945|X2=165|Y2=942|Y2_Frac=50000
|RECORD=6|OwnerIndex=115|IsNotAccesible=T|IndexInSheet=28|OwnerPartId=1|LineWidth=1|LocationCount=2|X1=165|Y1=945|X2=147|X2_Frac=50000|Y2=945
|RECORD=6|OwnerIndex=115|IsNotAccesible=T|IndexInSheet=29|OwnerPartId=1|LineWidth=1|LocationCount=2|X1=165|Y1=955|X2=165|Y2=945
|RECORD=6|OwnerIndex=115|IsNotAccesible=T|IndexInSheet=30|OwnerPartId=1|LineWidth=1|LocationCount=2|X1=147|X1_Frac=50000|Y1=955|X2=165|Y2=955
|RECORD=12|OwnerIndex=115|IsNotAccesible=T|IndexInSheet=31|OwnerPartId=1|Location.X=147|Location.X_Frac=50000|Location.Y=950|Radius=5|LineWidth=1|StartAngle=90.000|EndAngle=270.000|Color=16711680
|RECORD=2|OwnerIndex=115|OwnerPartId=1|FormalType=1|Electrical=4|PinConglomerate=48|PinLength=20|Location.X=170|Location.Y=930|Name=2|Designator=2|PinName_PositionConglomerate=16|Name_CustomFontID=1|PinDesignator_PositionConglomerate=16|Designator_CustomFontID=1|PinPropagationDelay=0.000000E+000
|RECORD=2|OwnerIndex=115|OwnerPartId=1|FormalType=1|Electrical=4|PinConglomerate=48|PinLength=20|Location.X=170|Location.Y=940|Name=3|Designator=3|PinName_PositionConglomerate=16|Name_CustomFontID=1|PinDesignator_PositionConglomerate=16|Designator_CustomFontID=1|PinPropagationDelay=0.000000E+000
|RECORD=2|OwnerIndex=115|OwnerPartId=1|FormalType=1|Electrical=4|PinConglomerate=48|PinLength=20|Location.X=170|Location.Y=950|Name=1|Designator=1|PinName_PositionConglomerate=16|Name_CustomFontID=1|PinDesignator_PositionConglomerate=16|Designator_CustomFontID=1|PinPropagationDelay=0.000000E+000
|RECORD=34|OwnerIndex=115|IndexInSheet=-1|OwnerPartId=-1|Location.X=139|Location.X_Frac=99535|Location.Y=960|Location.Y_Frac=311|Color=8388608|FontID=3|Text=J1|Name=Designator|ReadOnlyState=1|OverrideNotAutoPosition=T
|RECORD=41|OwnerIndex=115|IndexInSheet=-1|OwnerPartId=-1|Location.X=139|Location.X_Frac=95138|Location.Y=919|Location.Y_Frac=96760|Color=8388608|FontID=2|IsHidden=T|Text=PJ-002A|Name=Comment|NotAutoPosition=T
|RECORD=44|OwnerIndex=115
|RECORD=45|OwnerIndex=156|IndexInSheet=-1|Description=CONN, JACK, R/A TH, 2.1X5.5MM|UseComponentLibrary=T|ModelName=CUI_PJ-002A|ModelType=PCBLIB|DatafileCount=1|ModelDatafileEntity0=CUI_PJ-002A|ModelDatafileKind0=PCBLib|IsCurrent=T|DatalinksLocked=T|DatabaseDatalinksLocked=T|IntegratedModel=T|DatabaseModel=T
|RECORD=46|OwnerIndex=157
|RECORD=48|OwnerIndex=157
|RECORD=1|LibReference=DFLZ39|ComponentDescription=DIO, ZENER, DFLZ39, 39V, 5%, 1W, SOD123FL|PartCount=2|DisplayModeCount=1|IndexInSheet=49|OwnerPartId=-1|Location.X=260|Location.Y=950|Orientation=3|CurrentPartId=1|LibraryPath=*|SourceLibraryName=Passives.IntLib|TargetFileName=*|AreaColor=11599871|Color=128|PartIDLocked=F|DesignItemId=DFLZ39|AllPinCount=2
|RECORD=41|OwnerIndex=160|OwnerPartId=-1|Location.X=258|Location.Y=961|Color=8388608|FontID=2|IsHidden=T|Text=DFLZ39-TP|Name=MFG PART NUM
|RECORD=41|OwnerIndex=160|IndexInSheet=1|OwnerPartId=-1|Location.X=258|Location.Y=961|Color=8388608|FontID=2|IsHidden=T|Text=9/4/2013|Name=MODIFY DATE
|RECORD=41|OwnerIndex=160|IndexInSheet=2|OwnerPartId=-1|Location.X=258|Location.Y=961|Color=8388608|FontID=2|IsHidden=T|Text=MICRO COMM|Name=MFG NAME
|RECORD=41|OwnerIndex=160|IndexInSheet=3|OwnerPartId=-1|Location.X=258|Location.Y=961|Color=8388608|FontID=2|IsHidden=T|Text=DIO, ZENER|Name=CATEGORY
|RECORD=41|OwnerIndex=160|IndexInSheet=4|OwnerPartId=-1|Location.X=258|Location.Y=961|Color=8388608|FontID=2|IsHidden=T|Name=DATE
|RECORD=41|OwnerIndex=160|IndexInSheet=5|OwnerPartId=-1|Location.X=258|Location.Y=961|Color=8388608|FontID=2|IsHidden=T|Text=150C|Name=MAXTEMP
|RECORD=41|OwnerIndex=160|IndexInSheet=6|OwnerPartId=-1|Location.X=258|Location.Y=961|Color=8388608|FontID=2|IsHidden=T|Text=-55C|Name=MINTEMP
|RECORD=41|OwnerIndex=160|IndexInSheet=7|OwnerPartId=-1|Location.X=258|Location.Y=961|Color=8388608|FontID=2|IsHidden=T|Text=SERIES|Name=OTHER
|RECORD=41|OwnerIndex=160|IndexInSheet=8|OwnerPartId=-1|Location.X=258|Location.Y=961|Color=8388608|FontID=2|IsHidden=T|Text=5%|Name=P2
|RECORD=41|OwnerIndex=160|IndexInSheet=9|OwnerPartId=-1|Location.X=258|Location.Y=961|Color=8388608|FontID=2|IsHidden=T|Text=1W|Name=P3
|RECORD=41|OwnerIndex=160|IndexInSheet=10|OwnerPartId=-1|Location.X=258|Location.Y=961|Color=8388608|FontID=2|IsHidden=T|Text=SOD123FL|Name=SIZE
|RECORD=41|OwnerIndex=160|IndexInSheet=11|OwnerPartId=-1|Location.X=258|Location.Y=961|Color=8388608|FontID=2|IsHidden=T|Name=SUB
|RECORD=41|OwnerIndex=160|IndexInSheet=12|OwnerPartId=-1|Location.X=258|Location.Y=961|Color=8388608|FontID=1|IsHidden=T|Text=*|Name=SHEETPART
|RECORD=41|OwnerIndex=160|IndexInSheet=13|OwnerPartId=-1|Location.X=258|Location.Y=961|Color=8388608|FontID=1|IsHidden=T|Text=DIO, ZENER, DFLZ39, 39V, 5%, 1W, SOD123FL|Name=DESC
|RECORD=41|OwnerIndex=160|IndexInSheet=14|OwnerPartId=-1|Location.X=258|Location.Y=961|Color=8388608|FontID=1|IsHidden=T|Text=Digi-Key|Name=Supplier 1|ReadOnlyState=3
|RECORD=41|OwnerIndex=160|IndexInSheet=15|OwnerPartId=-1|Location.X=258|Location.Y=961|Color=8388608|FontID=1|IsHidden=T|Text=DFLZ39-TPMSDKR-ND|Name=Supplier Part Number 1|ReadOnlyState=3
|RECORD=41|OwnerIndex=160|IndexInSheet=16|OwnerPartId=-1|Location.X=279|Location.Y=927|Color=8388608|FontID=2|Text=39V|Name=P1
|RECORD=41|OwnerIndex=160|IndexInSheet=17|OwnerPartId=-1|Location.X=279|Location.Y=915|Color=8388608|FontID=2|Text=DFLZ39|Name=VALUE
|RECORD=2|OwnerIndex=160|OwnerPartId=1|FormalType=1|Electrical=4|PinConglomerate=34|PinLength=20|Location.X=280|Location.Y=950|Name=A|Designator=2|SwapIdPin=2|SwapIDPart=1|PinPropagationDelay=0.000000E+000
|RECORD=2|OwnerIndex=160|OwnerPartId=1|FormalType=1|Electrical=4|PinConglomerate=32|PinLength=20|Location.X=300|Location.Y=950|Name=C|Designator=1|SwapIdPin=1|SwapIDPart=1|PinPropagationDelay=0.000000E+000
|RECORD=13|OwnerIndex=160|IsNotAccesible=T|IndexInSheet=20|OwnerPartId=1|Location.X=283|Location.X_Frac=70000|Location.Y=950|Corner.X=280|Corner.Y=950|LineWidth=1|Color=16711680
|RECORD=13|OwnerIndex=160|IsNotAccesible=T|IndexInSheet=21|OwnerPartId=1|Location.X=300|Location.Y=950|Corner.X=296|Corner.X_Frac=20000|Corner.Y=950|LineWidth=1|Color=16711680
|RECORD=13|OwnerIndex=160|IsNotAccesible=T|IndexInSheet=22|OwnerPartId=1|Location.X=296|Location.X_Frac=20000|Location.Y=957|Location.Y_Frac=50000|Corner.X=293|Corner.X_Frac=70000|Corner.Y=960|LineWidth=1|Color=16711680
|RECORD=13|OwnerIndex=160|IsNotAccesible=T|IndexInSheet=23|OwnerPartId=1|Location.X=298|Location.X_Frac=70000|Location.Y=940|Corner.X=296|Corner.X_Frac=20000|Corner.Y=942|Corner.Y_Frac=50000|LineWidth=1|Color=16711680
|RECORD=13|OwnerIndex=160|IsNotAccesible=T|IndexInSheet=24|OwnerPartId=1|Location.X=296|Location.X_Frac=20000|Location.Y=957|Location.Y_Frac=50000|Corner.X=296|Corner.X_Frac=20000|Corner.Y=942|Corner.Y_Frac=50000|LineWidth=1|Color=16711680
|RECORD=7|OwnerIndex=160|IsNotAccesible=T|IndexInSheet=25|OwnerPartId=1|LineWidth=1|Color=16711680|AreaColor=16711680|IsSolid=T|LocationCount=3|X1=296|X1_Frac=20000|Y1=950|X2=283|X2_Frac=70000|Y2=957|Y2_Frac=50000|X3=283|X3_Frac=70000|Y3=942|Y3_Frac=50000
|RECORD=41|OwnerIndex=160|IndexInSheet=26|OwnerPartId=-1|Location.X=258|Location.Y=961|Color=8388608|FontID=1|IsHidden=T|Text=<VALENTIUM>|Name=VALENTIUM PART NUM
|RECORD=34|OwnerIndex=160|IndexInSheet=-1|OwnerPartId=-1|Location.X=279|Location.Y=961|Color=8388608|FontID=3|Text=D1|Name=Designator|ReadOnlyState=1
|RECORD=41|OwnerIndex=160|IndexInSheet=-1|OwnerPartId=-1|Location.X=258|Location.Y=961|Color=8388608|FontID=2|IsHidden=T|Text=="MFG PART NUM"|Name=Comment
|RECORD=44|OwnerIndex=160
|RECORD=45|OwnerIndex=192|IndexInSheet=-1|Description=SODFL, SOD-123FL, 2-Leads, Body 1.65x3.70mm, IPC Medium Density|UseComponentLibrary=T|ModelName=SODFL370X135-2N|ModelType=PCBLIB|DatafileCount=1|ModelDatafileEntity0=SODFL370X135-2N|ModelDatafileKind0=PCBLib|IsCurrent=T|DatalinksLocked=T|DatabaseDatalinksLocked=T|IntegratedModel=T|DatabaseModel=T
|RECORD=46|OwnerIndex=193
|RECORD=48|OwnerIndex=193
|RECORD=1|LibReference=DFLZ39|ComponentDescription=DIO, ZENER, DFLZ39, 39V, 5%, 1W, SOD123FL|PartCount=2|DisplayModeCount=1|IndexInSheet=50|OwnerPartId=-1|Location.X=260|Location.Y=840|Orientation=3|CurrentPartId=1|LibraryPath=*|SourceLibraryName=Passives.IntLib|TargetFileName=*|AreaColor=11599871|Color=128|PartIDLocked=F|DesignItemId=DFLZ39|AllPinCount=2
|RECORD=41|OwnerIndex=196|OwnerPartId=-1|Location.X=258|Location.Y=851|Color=8388608|FontID=2|IsHidden=T|Text=DFLZ39-TP|Name=MFG PART NUM
|RECORD=41|OwnerIndex=196|IndexInSheet=1|OwnerPartId=-1|Location.X=258|Location.Y=851|Color=8388608|FontID=2|IsHidden=T|Text=9/4/2013|Name=MODIFY DATE
|RECORD=41|OwnerIndex=196|IndexInSheet=2|OwnerPartId=-1|Location.X=258|Location.Y=851|Color=8388608|FontID=2|IsHidden=T|Text=MICRO COMM|Name=MFG NAME
|RECORD=41|OwnerIndex=196|IndexInSheet=3|OwnerPartId=-1|Location.X=258|Location.Y=851|Color=8388608|FontID=2|IsHidden=T|Text=DIO, ZENER|Name=CATEGORY
|RECORD=41|OwnerIndex=196|IndexInSheet=4|OwnerPartId=-1|Location.X=258|Location.Y=851|Color=8388608|FontID=2|IsHidden=T|Name=DATE
|RECORD=41|OwnerIndex=196|IndexInSheet=5|OwnerPartId=-1|Location.X=258|Location.Y=851|Color=8388608|FontID=2|IsHidden=T|Text=150C|Name=MAXTEMP
|RECORD=41|OwnerIndex=196|IndexInSheet=6|OwnerPartId=-1|Location.X=258|Location.Y=851|Color=8388608|FontID=2|IsHidden=T|Text=-55C|Name=MINTEMP
|RECORD=41|OwnerIndex=196|IndexInSheet=7|OwnerPartId=-1|Location.X=258|Location.Y=851|Color=8388608|FontID=2|IsHidden=T|Text=SERIES|Name=OTHER
|RECORD=41|OwnerIndex=196|IndexInSheet=8|OwnerPartId=-1|Location.X=258|Location.Y=851|Color=8388608|FontID=2|IsHidden=T|Text=5%|Name=P2
|RECORD=41|OwnerIndex=196|IndexInSheet=9|OwnerPartId=-1|Location.X=258|Location.Y=851|Color=8388608|FontID=2|IsHidden=T|Text=1W|Name=P3
|RECORD=41|OwnerIndex=196|IndexInSheet=10|OwnerPartId=-1|Location.X=258|Location.Y=851|Color=8388608|FontID=2|IsHidden=T|Text=SOD123FL|Name=SIZE
|RECORD=41|OwnerIndex=196|IndexInSheet=11|OwnerPartId=-1|Location.X=258|Location.Y=851|Color=8388608|FontID=2|IsHidden=T|Name=SUB
|RECORD=41|OwnerIndex=196|IndexInSheet=12|OwnerPartId=-1|Location.X=258|Location.Y=851|Color=8388608|FontID=1|IsHidden=T|Text=*|Name=SHEETPART
|RECORD=41|OwnerIndex=196|IndexInSheet=13|OwnerPartId=-1|Location.X=258|Location.Y=851|Color=8388608|FontID=1|IsHidden=T|Text=DIO, ZENER, DFLZ39, 39V, 5%, 1W, SOD123FL|Name=DESC
|RECORD=41|OwnerIndex=196|IndexInSheet=14|OwnerPartId=-1|Location.X=258|Location.Y=851|Color=8388608|FontID=1|IsHidden=T|Text=Digi-Key|Name=Supplier 1|ReadOnlyState=3
|RECORD=41|OwnerIndex=196|IndexInSheet=15|OwnerPartId=-1|Location.X=258|Location.Y=851|Color=8388608|FontID=1|IsHidden=T|Text=DFLZ39-TPMSDKR-ND|Name=Supplier Part Number 1|ReadOnlyState=3
|RECORD=41|OwnerIndex=196|IndexInSheet=16|OwnerPartId=-1|Location.X=279|Location.Y=817|Color=8388608|FontID=2|Text=39V|Name=P1
|RECORD=41|OwnerIndex=196|IndexInSheet=17|OwnerPartId=-1|Location.X=279|Location.Y=805|Color=8388608|FontID=2|Text=DFLZ39|Name=VALUE
|RECORD=2|OwnerIndex=196|OwnerPartId=1|FormalType=1|Electrical=4|PinConglomerate=34|PinLength=20|Location.X=280|Location.Y=840|Name=A|Designator=2|SwapIdPin=2|SwapIDPart=1|PinPropagationDelay=0.000000E+000
|RECORD=2|OwnerIndex=196|OwnerPartId=1|FormalType=1|Electrical=4|PinConglomerate=32|PinLength=20|Location.X=300|Location.Y=840|Name=C|Designator=1|SwapIdPin=1|SwapIDPart=1|PinPropagationDelay=0.000000E+000
|RECORD=13|OwnerIndex=196|IsNotAccesible=T|IndexInSheet=20|OwnerPartId=1|Location.X=283|Location.X_Frac=70000|Location.Y=840|Corner.X=280|Corner.Y=840|LineWidth=1|Color=16711680
|RECORD=13|OwnerIndex=196|IsNotAccesible=T|IndexInSheet=21|OwnerPartId=1|Location.X=300|Location.Y=840|Corner.X=296|Corner.X_Frac=20000|Corner.Y=840|LineWidth=1|Color=16711680
|RECORD=13|OwnerIndex=196|IsNotAccesible=T|IndexInSheet=22|OwnerPartId=1|Location.X=296|Location.X_Frac=20000|Location.Y=847|Location.Y_Frac=50000|Corner.X=293|Corner.X_Frac=70000|Corner.Y=850|LineWidth=1|Color=16711680
|RECORD=13|OwnerIndex=196|IsNotAccesible=T|IndexInSheet=23|OwnerPartId=1|Location.X=298|Location.X_Frac=70000|Location.Y=830|Corner.X=296|Corner.X_Frac=20000|Corner.Y=832|Corner.Y_Frac=50000|LineWidth=1|Color=16711680
|RECORD=13|OwnerIndex=196|IsNotAccesible=T|IndexInSheet=24|OwnerPartId=1|Location.X=296|Location.X_Frac=20000|Location.Y=847|Location.Y_Frac=50000|Corner.X=296|Corner.X_Frac=20000|Corner.Y=832|Corner.Y_Frac=50000|LineWidth=1|Color=16711680
|RECORD=7|OwnerIndex=196|IsNotAccesible=T|IndexInSheet=25|OwnerPartId=1|LineWidth=1|Color=16711680|AreaColor=16711680|IsSolid=T|LocationCount=3|X1=296|X1_Frac=20000|Y1=840|X2=283|X2_Frac=70000|Y2=847|Y2_Frac=50000|X3=283|X3_Frac=70000|Y3=832|Y3_Frac=50000
|RECORD=41|OwnerIndex=196|IndexInSheet=26|OwnerPartId=-1|Location.X=258|Location.Y=851|Color=8388608|FontID=1|IsHidden=T|Text=<VALENTIUM>|Name=VALENTIUM PART NUM
|RECORD=34|OwnerIndex=196|IndexInSheet=-1|OwnerPartId=-1|Location.X=279|Location.Y=851|Color=8388608|FontID=3|Text=D2|Name=Designator|ReadOnlyState=1
|RECORD=41|OwnerIndex=196|IndexInSheet=-1|OwnerPartId=-1|Location.X=258|Location.Y=851|Color=8388608|FontID=2|IsHidden=T|Text=="MFG PART NUM"|Name=Comment
|RECORD=44|OwnerIndex=196
|RECORD=45|OwnerIndex=228|IndexInSheet=-1|Description=SODFL, SOD-123FL, 2-Leads, Body 1.65x3.70mm, IPC Medium Density|UseComponentLibrary=T|ModelName=SODFL370X135-2N|ModelType=PCBLIB|DatafileCount=1|ModelDatafileEntity0=SODFL370X135-2N|ModelDatafileKind0=PCBLib|IsCurrent=T|DatalinksLocked=T|DatabaseDatalinksLocked=T|IntegratedModel=T|DatabaseModel=T
|RECORD=46|OwnerIndex=229
|RECORD=48|OwnerIndex=229
|RECORD=1|LibReference=DFLZ39|ComponentDescription=DIO, ZENER, DFLZ39, 39V, 5%, 1W, SOD123FL|PartCount=2|DisplayModeCount=1|IndexInSheet=51|OwnerPartId=-1|Location.X=180|Location.Y=670|Orientation=3|CurrentPartId=1|LibraryPath=*|SourceLibraryName=Passives.IntLib|TargetFileName=*|AreaColor=11599871|Color=128|PartIDLocked=F|DesignItemId=DFLZ39|AllPinCount=2
|RECORD=41|OwnerIndex=232|OwnerPartId=-1|Location.X=178|Location.Y=681|Color=8388608|FontID=2|IsHidden=T|Text=DFLZ39-TP|Name=MFG PART NUM
|RECORD=41|OwnerIndex=232|IndexInSheet=1|OwnerPartId=-1|Location.X=178|Location.Y=681|Color=8388608|FontID=2|IsHidden=T|Text=9/4/2013|Name=MODIFY DATE
|RECORD=41|OwnerIndex=232|IndexInSheet=2|OwnerPartId=-1|Location.X=178|Location.Y=681|Color=8388608|FontID=2|IsHidden=T|Text=MICRO COMM|Name=MFG NAME
|RECORD=41|OwnerIndex=232|IndexInSheet=3|OwnerPartId=-1|Location.X=178|Location.Y=681|Color=8388608|FontID=2|IsHidden=T|Text=DIO, ZENER|Name=CATEGORY
|RECORD=41|OwnerIndex=232|IndexInSheet=4|OwnerPartId=-1|Location.X=178|Location.Y=681|Color=8388608|FontID=2|IsHidden=T|Name=DATE
|RECORD=41|OwnerIndex=232|IndexInSheet=5|OwnerPartId=-1|Location.X=178|Location.Y=681|Color=8388608|FontID=2|IsHidden=T|Text=150C|Name=MAXTEMP
|RECORD=41|OwnerIndex=232|IndexInSheet=6|OwnerPartId=-1|Location.X=178|Location.Y=681|Color=8388608|FontID=2|IsHidden=T|Text=-55C|Name=MINTEMP
|RECORD=41|OwnerIndex=232|IndexInSheet=7|OwnerPartId=-1|Location.X=178|Location.Y=681|Color=8388608|FontID=2|IsHidden=T|Text=SERIES|Name=OTHER
|RECORD=41|OwnerIndex=232|IndexInSheet=8|OwnerPartId=-1|Location.X=178|Location.Y=681|Color=8388608|FontID=2|IsHidden=T|Text=5%|Name=P2
|RECORD=41|OwnerIndex=232|IndexInSheet=9|OwnerPartId=-1|Location.X=178|Location.Y=681|Color=8388608|FontID=2|IsHidden=T|Text=1W|Name=P3
|RECORD=41|OwnerIndex=232|IndexInSheet=10|OwnerPartId=-1|Location.X=178|Location.Y=681|Color=8388608|FontID=2|IsHidden=T|Text=SOD123FL|Name=SIZE
|RECORD=41|OwnerIndex=232|IndexInSheet=11|OwnerPartId=-1|Location.X=178|Location.Y=681|Color=8388608|FontID=2|IsHidden=T|Name=SUB
|RECORD=41|OwnerIndex=232|IndexInSheet=12|OwnerPartId=-1|Location.X=178|Location.Y=681|Color=8388608|FontID=1|IsHidden=T|Text=*|Name=SHEETPART
|RECORD=41|OwnerIndex=232|IndexInSheet=13|OwnerPartId=-1|Location.X=178|Location.Y=681|Color=8388608|FontID=1|IsHidden=T|Text=DIO, ZENER, DFLZ39, 39V, 5%, 1W, SOD123FL|Name=DESC
|RECORD=41|OwnerIndex=232|IndexInSheet=14|OwnerPartId=-1|Location.X=178|Location.Y=681|Color=8388608|FontID=1|IsHidden=T|Text=Digi-Key|Name=Supplier 1|ReadOnlyState=3
|RECORD=41|OwnerIndex=232|IndexInSheet=15|OwnerPartId=-1|Location.X=178|Location.Y=681|Color=8388608|FontID=1|IsHidden=T|Text=DFLZ39-TPMSDKR-ND|Name=Supplier Part Number 1|ReadOnlyState=3
|RECORD=41|OwnerIndex=232|IndexInSheet=16|OwnerPartId=-1|Location.X=199|Location.Y=647|Color=8388608|FontID=2|Text=39V|Name=P1
|RECORD=41|OwnerIndex=232|IndexInSheet=17|OwnerPartId=-1|Location.X=199|Location.Y=635|Color=8388608|FontID=2|Text=DFLZ39|Name=VALUE
|RECORD=2|OwnerIndex=232|OwnerPartId=1|FormalType=1|Electrical=4|PinConglomerate=34|PinLength=20|Location.X=200|Location.Y=670|Name=A|Designator=2|SwapIdPin=2|SwapIDPart=1|PinPropagationDelay=0.000000E+000
|RECORD=2|OwnerIndex=232|OwnerPartId=1|FormalType=1|Electrical=4|PinConglomerate=32|PinLength=20|Location.X=220|Location.Y=670|Name=C|Designator=1|SwapIdPin=1|SwapIDPart=1|PinPropagationDelay=0.000000E+000
|RECORD=13|OwnerIndex=232|IsNotAccesible=T|IndexInSheet=20|OwnerPartId=1|Location.X=203|Location.X_Frac=70000|Location.Y=670|Corner.X=200|Corner.Y=670|LineWidth=1|Color=16711680
|RECORD=13|OwnerIndex=232|IsNotAccesible=T|IndexInSheet=21|OwnerPartId=1|Location.X=220|Location.Y=670|Corner.X=216|Corner.X_Frac=20000|Corner.Y=670|LineWidth=1|Color=16711680
|RECORD=13|OwnerIndex=232|IsNotAccesible=T|IndexInSheet=22|OwnerPartId=1|Location.X=216|Location.X_Frac=20000|Location.Y=677|Location.Y_Frac=50000|Corner.X=213|Corner.X_Frac=70000|Corner.Y=680|LineWidth=1|Color=16711680
|RECORD=13|OwnerIndex=232|IsNotAccesible=T|IndexInSheet=23|OwnerPartId=1|Location.X=218|Location.X_Frac=70000|Location.Y=660|Corner.X=216|Corner.X_Frac=20000|Corner.Y=662|Corner.Y_Frac=50000|LineWidth=1|Color=16711680
|RECORD=13|OwnerIndex=232|IsNotAccesible=T|IndexInSheet=24|OwnerPartId=1|Location.X=216|Location.X_Frac=20000|Location.Y=677|Location.Y_Frac=50000|Corner.X=216|Corner.X_Frac=20000|Corner.Y=662|Corner.Y_Frac=50000|LineWidth=1|Color=16711680
|RECORD=7|OwnerIndex=232|IsNotAccesible=T|IndexInSheet=25|OwnerPartId=1|LineWidth=1|Color=16711680|AreaColor=16711680|IsSolid=T|LocationCount=3|X1=216|X1_Frac=20000|Y1=670|X2=203|X2_Frac=70000|Y2=677|Y2_Frac=50000|X3=203|X3_Frac=70000|Y3=662|Y3_Frac=50000
|RECORD=41|OwnerIndex=232|IndexInSheet=26|OwnerPartId=-1|Location.X=178|Location.Y=681|Color=8388608|FontID=1|IsHidden=T|Text=<VALENTIUM>|Name=VALENTIUM PART NUM
|RECORD=34|OwnerIndex=232|IndexInSheet=-1|OwnerPartId=-1|Location.X=199|Location.Y=681|Color=8388608|FontID=3|Text=D3|Name=Designator|ReadOnlyState=1
|RECORD=41|OwnerIndex=232|IndexInSheet=-1|OwnerPartId=-1|Location.X=178|Location.Y=681|Color=8388608|FontID=2|IsHidden=T|Text=="MFG PART NUM"|Name=Comment
|RECORD=44|OwnerIndex=232
|RECORD=45|OwnerIndex=264|IndexInSheet=-1|Description=SODFL, SOD-123FL, 2-Leads, Body 1.65x3.70mm, IPC Medium Density|UseComponentLibrary=T|ModelName=SODFL370X135-2N|ModelType=PCBLIB|DatafileCount=1|ModelDatafileEntity0=SODFL370X135-2N|ModelDatafileKind0=PCBLib|IsCurrent=T|DatalinksLocked=T|DatabaseDatalinksLocked=T|IntegratedModel=T|DatabaseModel=T
|RECORD=46|OwnerIndex=265
|RECORD=48|OwnerIndex=265
|RECORD=1|LibReference=39-30-1060|ComponentDescription=CONN, HDR, 2X3, R/A, 4.2MM, TH, MINI-FIT JR|PartCount=2|DisplayModeCount=1|IndexInSheet=52|OwnerPartId=-1|Location.X=160|Location.Y=840|IsMirrored=T|CurrentPartId=1|LibraryPath=*|SourceLibraryName=Connectors.IntLib|TargetFileName=*|AreaColor=11599871|Color=128|PartIDLocked=F|DesignItemId=39-30-1060|AllPinCount=6
|RECORD=41|OwnerIndex=268|OwnerPartId=-1|Location.X=99|Location.Y=846|Color=8388608|FontID=2|IsHidden=T|Text=10/10/2013|Name=MODIFY DATE|IsMirrored=T
|RECORD=41|OwnerIndex=268|IndexInSheet=1|OwnerPartId=-1|Location.X=99|Location.Y=846|Color=8388608|FontID=2|IsHidden=T|Text=105314-1206|Name=MFG PART NUM|IsMirrored=T
|RECORD=41|OwnerIndex=268|IndexInSheet=2|OwnerPartId=-1|Location.X=99|Location.Y=846|Color=8388608|FontID=2|IsHidden=T|Text=MOLEX|Name=MFG NAME|IsMirrored=T
|RECORD=41|OwnerIndex=268|IndexInSheet=3|OwnerPartId=-1|Location.X=99|Location.Y=846|Color=8388608|FontID=2|IsHidden=T|Text=CONN, HDR|Name=CATEGORY|IsMirrored=T
|RECORD=41|OwnerIndex=268|IndexInSheet=4|OwnerPartId=-1|Location.X=99|Location.Y=846|Color=8388608|FontID=2|IsHidden=T|Text=105C|Name=MAXTEMP|IsMirrored=T
|RECORD=41|OwnerIndex=268|IndexInSheet=5|OwnerPartId=-1|Location.X=99|Location.Y=846|Color=8388608|FontID=2|IsHidden=T|Text=-40C|Name=MINTEMP|IsMirrored=T
|RECORD=41|OwnerIndex=268|IndexInSheet=6|OwnerPartId=-1|Location.X=99|Location.Y=846|Color=8388608|FontID=2|IsHidden=T|Text=NANO-FIT|Name=OTHER|IsMirrored=T
|RECORD=41|OwnerIndex=268|IndexInSheet=7|OwnerPartId=-1|Location.X=99|Location.Y=846|Color=8388608|FontID=2|IsHidden=T|Text=R/A|Name=P1|IsMirrored=T
|RECORD=41|OwnerIndex=268|IndexInSheet=8|OwnerPartId=-1|Location.X=99|Location.Y=846|Color=8388608|FontID=2|IsHidden=T|Text=2.5MM|Name=P2|IsMirrored=T
|RECORD=41|OwnerIndex=268|IndexInSheet=9|OwnerPartId=-1|Location.X=99|Location.Y=846|Color=8388608|FontID=2|IsHidden=T|Name=P3|IsMirrored=T
|RECORD=41|OwnerIndex=268|IndexInSheet=10|OwnerPartId=-1|Location.X=99|Location.Y=846|Color=8388608|FontID=2|IsHidden=T|Text=TH|Name=SIZE|IsMirrored=T
|RECORD=41|OwnerIndex=268|IndexInSheet=11|OwnerPartId=-1|Location.X=99|Location.Y=846|Color=8388608|FontID=2|IsHidden=T|Name=SUB|IsMirrored=T
|RECORD=41|OwnerIndex=268|IndexInSheet=12|OwnerPartId=-1|Location.X=99|Location.Y=846|Color=8388608|FontID=2|IsHidden=T|Name=SHEETPART|IsMirrored=T
|RECORD=41|OwnerIndex=268|IndexInSheet=13|OwnerPartId=-1|Location.X=99|Location.Y=846|Color=8388608|FontID=2|IsHidden=T|Name=DATE|IsMirrored=T
|RECORD=41|OwnerIndex=268|IndexInSheet=14|OwnerPartId=-1|Location.X=99|Location.Y=846|Color=8388608|FontID=1|IsHidden=T|Text=CONN, HDR, 2X3, R/A, 2.5MM, TH, NANO-FIT|Name=DESC|IsMirrored=T
|RECORD=41|OwnerIndex=268|IndexInSheet=15|OwnerPartId=-1|Location.X=99|Location.Y=846|Color=8388608|FontID=1|IsHidden=T|Text=Digi-Key|Name=Supplier 1|ReadOnlyState=3|IsMirrored=T
|RECORD=41|OwnerIndex=268|IndexInSheet=16|OwnerPartId=-1|Location.X=99|Location.Y=846|Color=8388608|FontID=1|IsHidden=T|Text=WM14977-ND|Name=Supplier Part Number 1|ReadOnlyState=3|IsMirrored=T
|RECORD=41|OwnerIndex=268|IndexInSheet=17|OwnerPartId=-1|Location.X=99|Location.Y=846|Color=8388608|FontID=1|IsHidden=T|Text=<VALENTIUM>|Name=VALENTIUM PART NUM|IsMirrored=T
|RECORD=41|OwnerIndex=268|IndexInSheet=18|OwnerPartId=-1|Location.X=99|Location.Y=772|Color=8388608|FontID=2|Text=2X3|Name=VALUE|IsMirrored=T
|RECORD=2|OwnerIndex=268|OwnerPartId=1|FormalType=1|Electrical=4|PinConglomerate=56|PinLength=30|Location.X=130|Location.Y=790|Designator=6|SwapIdPin=6|SwapIDPart=1|PinPropagationDelay=0.000000E+000
|RECORD=2|OwnerIndex=268|OwnerPartId=1|FormalType=1|Electrical=4|PinConglomerate=56|PinLength=30|Location.X=130|Location.Y=800|Designator=5|SwapIdPin=5|SwapIDPart=1|PinPropagationDelay=0.000000E+000
|RECORD=2|OwnerIndex=268|OwnerPartId=1|FormalType=1|Electrical=4|PinConglomerate=56|PinLength=30|Location.X=130|Location.Y=810|Designator=4|SwapIdPin=4|SwapIDPart=1|PinPropagationDelay=0.000000E+000
|RECORD=2|OwnerIndex=268|OwnerPartId=1|FormalType=1|Electrical=4|PinConglomerate=56|PinLength=30|Location.X=130|Location.Y=820|Designator=3|SwapIdPin=3|SwapIDPart=1|PinPropagationDelay=0.000000E+000
|RECORD=2|OwnerIndex=268|OwnerPartId=1|FormalType=1|Electrical=4|PinConglomerate=56|PinLength=30|Location.X=130|Location.Y=830|Designator=2|SwapIdPin=2|SwapIDPart=1|PinPropagationDelay=0.000000E+000
|RECORD=2|OwnerIndex=268|OwnerPartId=1|FormalType=1|Electrical=4|PinConglomerate=56|PinLength=30|Location.X=130|Location.Y=840|Designator=1|SwapIdPin=1|SwapIDPart=1|PinPropagationDelay=0.000000E+000
|RECORD=13|OwnerIndex=268|IsNotAccesible=T|IndexInSheet=25|OwnerPartId=1|Location.X=123|Location.Y=840|Corner.X=130|Corner.Y=840|LineWidth=1|Color=16711680
|RECORD=13|OwnerIndex=268|IsNotAccesible=T|IndexInSheet=26|OwnerPartId=1|Location.X=117|Location.Y=840|Corner.X=123|Corner.Y=840|LineWidth=1|Color=16711680
|RECORD=13|OwnerIndex=268|IsNotAccesible=T|IndexInSheet=27|OwnerPartId=1|Location.X=123|Location.Y=830|Corner.X=130|Corner.Y=830|LineWidth=1|Color=16711680
|RECORD=13|OwnerIndex=268|IsNotAccesible=T|IndexInSheet=28|OwnerPartId=1|Location.X=117|Location.Y=830|Corner.X=123|Corner.Y=830|LineWidth=1|Color=16711680
|RECORD=13|OwnerIndex=268|IsNotAccesible=T|IndexInSheet=29|OwnerPartId=1|Location.X=122|Location.Y=835|Corner.X=117|Corner.Y=830|LineWidth=1|Color=16711680
|RECORD=13|OwnerIndex=268|IsNotAccesible=T|IndexInSheet=30|OwnerPartId=1|Location.X=122|Location.Y=835|Corner.X=117|Corner.Y=840|LineWidth=1|Color=16711680
|RECORD=13|OwnerIndex=268|IsNotAccesible=T|IndexInSheet=31|OwnerPartId=1|Location.X=122|Location.Y=845|Corner.X=117|Corner.Y=840|LineWidth=1|Color=16711680
|RECORD=13|OwnerIndex=268|IsNotAccesible=T|IndexInSheet=32|OwnerPartId=1|Location.X=122|Location.Y=825|Corner.X=117|Corner.Y=830|LineWidth=1|Color=16711680
|RECORD=13|OwnerIndex=268|IsNotAccesible=T|IndexInSheet=33|OwnerPartId=1|Location.X=123|Location.Y=820|Corner.X=130|Corner.Y=820|LineWidth=1|Color=16711680
|RECORD=13|OwnerIndex=268|IsNotAccesible=T|IndexInSheet=34|OwnerPartId=1|Location.X=117|Location.Y=820|Corner.X=123|Corner.Y=820|LineWidth=1|Color=16711680
|RECORD=13|OwnerIndex=268|IsNotAccesible=T|IndexInSheet=35|OwnerPartId=1|Location.X=123|Location.Y=810|Corner.X=130|Corner.Y=810|LineWidth=1|Color=16711680
|RECORD=13|OwnerIndex=268|IsNotAccesible=T|IndexInSheet=36|OwnerPartId=1|Location.X=117|Location.Y=810|Corner.X=123|Corner.Y=810|LineWidth=1|Color=16711680
|RECORD=13|OwnerIndex=268|IsNotAccesible=T|IndexInSheet=37|OwnerPartId=1|Location.X=122|Location.Y=815|Corner.X=117|Corner.Y=810|LineWidth=1|Color=16711680
|RECORD=13|OwnerIndex=268|IsNotAccesible=T|IndexInSheet=38|OwnerPartId=1|Location.X=122|Location.Y=815|Corner.X=117|Corner.Y=820|LineWidth=1|Color=16711680
|RECORD=13|OwnerIndex=268|IsNotAccesible=T|IndexInSheet=39|OwnerPartId=1|Location.X=122|Location.Y=825|Corner.X=117|Corner.Y=820|LineWidth=1|Color=16711680
|RECORD=13|OwnerIndex=268|IsNotAccesible=T|IndexInSheet=40|OwnerPartId=1|Location.X=122|Location.Y=805|Corner.X=117|Corner.Y=810|LineWidth=1|Color=16711680
|RECORD=13|OwnerIndex=268|IsNotAccesible=T|IndexInSheet=41|OwnerPartId=1|Location.X=123|Location.Y=800|Corner.X=130|Corner.Y=800|LineWidth=1|Color=16711680
|RECORD=13|OwnerIndex=268|IsNotAccesible=T|IndexInSheet=42|OwnerPartId=1|Location.X=117|Location.Y=800|Corner.X=123|Corner.Y=800|LineWidth=1|Color=16711680
|RECORD=13|OwnerIndex=268|IsNotAccesible=T|IndexInSheet=43|OwnerPartId=1|Location.X=123|Location.Y=790|Corner.X=130|Corner.Y=790|LineWidth=1|Color=16711680
|RECORD=13|OwnerIndex=268|IsNotAccesible=T|IndexInSheet=44|OwnerPartId=1|Location.X=117|Location.Y=790|Corner.X=123|Corner.Y=790|LineWidth=1|Color=16711680
|RECORD=13|OwnerIndex=268|IsNotAccesible=T|IndexInSheet=45|OwnerPartId=1|Location.X=122|Location.Y=795|Corner.X=117|Corner.Y=790|LineWidth=1|Color=16711680
|RECORD=13|OwnerIndex=268|IsNotAccesible=T|IndexInSheet=46|OwnerPartId=1|Location.X=122|Location.Y=795|Corner.X=117|Corner.Y=800|LineWidth=1|Color=16711680
|RECORD=13|OwnerIndex=268|IsNotAccesible=T|IndexInSheet=47|OwnerPartId=1|Location.X=122|Location.Y=805|Corner.X=117|Corner.Y=800|LineWidth=1|Color=16711680
|RECORD=13|OwnerIndex=268|IsNotAccesible=T|IndexInSheet=48|OwnerPartId=1|Location.X=122|Location.Y=785|Corner.X=117|Corner.Y=790|LineWidth=1|Color=16711680
|RECORD=13|OwnerIndex=268|IsNotAccesible=T|IndexInSheet=49|OwnerPartId=1|Location.X=130|Location.Y=785|Corner.X=100|Corner.Y=785|LineWidth=1|Color=16711680
|RECORD=13|OwnerIndex=268|IsNotAccesible=T|IndexInSheet=50|OwnerPartId=1|Location.X=100|Location.Y=845|Corner.X=130|Corner.Y=845|LineWidth=1|Color=16711680
|RECORD=13|OwnerIndex=268|IsNotAccesible=T|IndexInSheet=51|OwnerPartId=1|Location.X=100|Location.Y=785|Corner.X=100|Corner.Y=845|LineWidth=1|Color=16711680
|RECORD=13|OwnerIndex=268|IsNotAccesible=T|IndexInSheet=52|OwnerPartId=1|Location.X=130|Location.Y=845|Corner.X=130|Corner.Y=785|LineWidth=1|Color=16711680
|RECORD=34|OwnerIndex=268|IndexInSheet=-1|OwnerPartId=-1|Location.X=99|Location.Y=846|Color=8388608|FontID=3|Text=J2|Name=Designator|ReadOnlyState=1|IsMirrored=T
|RECORD=41|OwnerIndex=268|IndexInSheet=-1|OwnerPartId=-1|Location.X=99|Location.Y=846|Color=8388608|FontID=2|IsHidden=T|Text=39-30-1060|Name=Comment|ReadOnlyState=1|IsMirrored=T
|RECORD=44|OwnerIndex=268
|RECORD=45|OwnerIndex=330|IndexInSheet=-1|Description=HDR 2X3 MINI-FIT JR R/A 4.2MM|UseComponentLibrary=T|ModelName=39-30-1060|ModelType=PCBLIB|DatafileCount=1|ModelDatafileEntity0=39-30-1060|ModelDatafileKind0=PCBLib|IsCurrent=T|DatalinksLocked=T|DatabaseDatalinksLocked=T|IntegratedModel=T|DatabaseModel=T
|RECORD=46|OwnerIndex=331
|RECORD=48|OwnerIndex=331
|RECORD=1|LibReference=L101011MS02Q|ComponentDescription=SW, SPST, 250V, 2A, SLIDE, ON-OFF, TH|PartCount=2|DisplayModeCount=1|IndexInSheet=53|OwnerPartId=-1|Location.X=360|Location.Y=950|CurrentPartId=1|LibraryPath=*|SourceLibraryName=Miscellaneous.IntLib|TargetFileName=*|AreaColor=11599871|Color=128|PartIDLocked=F|DesignItemId=L101011MS02Q|AllPinCount=2
|RECORD=41|OwnerIndex=334|OwnerPartId=-1|Location.X=359|Location.X_Frac=99996|Location.Y=949|Location.Y_Frac=99996|Color=8388608|FontID=2|IsHidden=T|Text=L101011MS02Q|Name=MFG PART NUM
|RECORD=41|OwnerIndex=334|IndexInSheet=1|OwnerPartId=-1|Location.X=359|Location.X_Frac=99996|Location.Y=949|Location.Y_Frac=99996|Color=8388608|FontID=2|IsHidden=T|Text=C&K|Name=MFG NAME
|RECORD=41|OwnerIndex=334|IndexInSheet=2|OwnerPartId=-1|Location.X=360|Location.Y=950|Color=8388608|FontID=2|IsHidden=T|Text=1/21/2014|Name=MODIFY DATE
|RECORD=41|OwnerIndex=334|IndexInSheet=3|OwnerPartId=-1|Location.X=348|Location.Y=978|Color=8388608|FontID=2|IsHidden=T|Text=SW|Name=CATEGORY
|RECORD=41|OwnerIndex=334|IndexInSheet=4|OwnerPartId=-1|Location.X=348|Location.Y=978|Color=8388608|FontID=2|IsHidden=T|Text=9/5/2013|Name=DATE
|RECORD=41|OwnerIndex=334|IndexInSheet=5|OwnerPartId=-1|Location.X=348|Location.Y=978|Color=8388608|FontID=2|IsHidden=T|Text=85C|Name=MAXTEMP
|RECORD=41|OwnerIndex=334|IndexInSheet=6|OwnerPartId=-1|Location.X=348|Location.Y=978|Color=8388608|FontID=2|IsHidden=T|Text=-25C|Name=MINTEMP
|RECORD=41|OwnerIndex=334|IndexInSheet=7|OwnerPartId=-1|Location.X=348|Location.Y=978|Color=8388608|FontID=2|IsHidden=T|Text=L101011MS02Q|Name=OTHER
|RECORD=41|OwnerIndex=334|IndexInSheet=8|OwnerPartId=-1|Location.X=348|Location.Y=978|Color=8388608|FontID=2|IsHidden=T|Text=250V|Name=P1
|RECORD=41|OwnerIndex=334|IndexInSheet=9|OwnerPartId=-1|Location.X=348|Location.Y=978|Color=8388608|FontID=2|IsHidden=T|Text=2A|Name=P2
|RECORD=41|OwnerIndex=334|IndexInSheet=10|OwnerPartId=-1|Location.X=348|Location.Y=978|Color=8388608|FontID=2|IsHidden=T|Text=SW, SPST, 250V, 2A, SLIDE, ON-OFF, TH|Name=P3
|RECORD=41|OwnerIndex=334|IndexInSheet=11|OwnerPartId=-1|Location.X=348|Location.Y=978|Color=8388608|FontID=2|IsHidden=T|Text=19.1X10.79MM|Name=SIZE
|RECORD=41|OwnerIndex=334|IndexInSheet=12|OwnerPartId=-1|Location.X=348|Location.Y=978|Color=8388608|FontID=2|IsHidden=T|Name=SUB
|RECORD=41|OwnerIndex=334|IndexInSheet=13|OwnerPartId=-1|Location.X=348|Location.Y=927|Color=8388608|FontID=1|IsHidden=T|Text=*|Name=SHEETPART
|RECORD=41|OwnerIndex=334|IndexInSheet=14|OwnerPartId=-1|Location.X=348|Location.Y=984|Color=8388608|FontID=1|IsHidden=T|Text=SW, SPST, 250V, 2A, SLIDE, ON-OFF, TH|Name=DESC
|RECORD=41|OwnerIndex=334|IndexInSheet=15|OwnerPartId=-1|Location.X=348|Location.Y=994|Color=8388608|FontID=1|IsHidden=T|Text=<VALENTIUM>|Name=VALENTIUM PART NUM
|RECORD=41|OwnerIndex=334|IndexInSheet=16|OwnerPartId=-1|Location.X=348|Location.Y=994|Color=8388608|FontID=1|IsHidden=T|Text=Digi-Key|Name=Supplier 1|ReadOnlyState=3
|RECORD=41|OwnerIndex=334|IndexInSheet=17|OwnerPartId=-1|Location.X=348|Location.Y=994|Color=8388608|FontID=1|IsHidden=T|Text=CKC5106-ND|Name=Supplier Part Number 1|ReadOnlyState=3
|RECORD=41|OwnerIndex=334|IndexInSheet=18|OwnerPartId=-1|Location.X=359|Location.Y=935|Color=8388608|FontID=2|Text=SW-SPST|Name=VALUE
|RECORD=2|OwnerIndex=334|OwnerPartId=1|FormalType=1|Electrical=4|PinConglomerate=56|PinLength=10|Location.X=400|Location.Y=950|Designator=1|SwapIdPin=1|SwapIDPart=1|PinPropagationDelay=0.000000E+000
|RECORD=2|OwnerIndex=334|OwnerPartId=1|FormalType=1|Electrical=4|PinConglomerate=58|PinLength=10|Location.X=360|Location.Y=950|Designator=2|SwapIdPin=2|SwapIDPart=1|PinPropagationDelay=0.000000E+000
|RECORD=12|OwnerIndex=334|IsNotAccesible=T|IndexInSheet=21|OwnerPartId=1|Location.X=388|Location.Y=950|Radius=1|Radius_Frac=50000|LineWidth=1|EndAngle=360.000|Color=16711680
|RECORD=13|OwnerIndex=334|IsNotAccesible=T|IndexInSheet=22|OwnerPartId=1|Location.X=400|Location.Y=950|Corner.X=389|Corner.X_Frac=50000|Corner.Y=950|LineWidth=1|Color=16711680
|RECORD=12|OwnerIndex=334|IsNotAccesible=T|IndexInSheet=23|OwnerPartId=1|Location.X=372|Location.Y=950|Radius=1|Radius_Frac=50000|LineWidth=1|EndAngle=360.000|Color=16711680
|RECORD=13|OwnerIndex=334|IsNotAccesible=T|IndexInSheet=24|OwnerPartId=1|Location.X=360|Location.Y=950|Corner.X=370|Corner.X_Frac=50000|Corner.Y=950|LineWidth=1|Color=16711680
|RECORD=13|OwnerIndex=334|IsNotAccesible=T|IndexInSheet=25|OwnerPartId=1|Location.X=388|Location.Y=958|Location.Y_Frac=50000|Corner.X=373|Corner.X_Frac=50000|Corner.Y=950|LineWidth=1|Color=16711680
|RECORD=34|OwnerIndex=334|IndexInSheet=-1|OwnerPartId=-1|Location.X=359|Location.Y=959|Location.Y_Frac=50000|Color=8388608|FontID=3|Text=SW1|Name=Designator|ReadOnlyState=1
|RECORD=41|OwnerIndex=334|IndexInSheet=-1|OwnerPartId=-1|Location.X=390|Location.Y=930|Color=8388608|FontID=2|IsHidden=T|Text=L101011MS02Q|Name=Comment
|RECORD=44|OwnerIndex=334
|RECORD=45|OwnerIndex=365|IndexInSheet=-1|Description=SPST, TH, 6 PINS|UseComponentLibrary=T|ModelName=L101011MS02Q|ModelType=PCBLIB|DatafileCount=1|ModelDatafileEntity0=L101011MS02Q|ModelDatafileKind0=PCBLib|IsCurrent=T|DatalinksLocked=T|DatabaseDatalinksLocked=T|IntegratedModel=T|DatabaseModel=T
|RECORD=46|OwnerIndex=366
|RECORD=48|OwnerIndex=366
|RECORD=1|LibReference=CAP_0805_10UF_25V|ComponentDescription=CAP, CER, 10.UF, 25V, 10%, X5R, 0805|PartCount=2|DisplayModeCount=1|IndexInSheet=54|OwnerPartId=-1|Location.X=610|Location.Y=880|CurrentPartId=1|LibraryPath=*|SourceLibraryName=Capacitors.IntLib|TargetFileName=*|AreaColor=11599871|Color=128|PartIDLocked=F|DesignItemId=CAP_0805_10UF_25V|AllPinCount=2
|RECORD=41|OwnerIndex=369|OwnerPartId=-1|Location.X=610|Location.Y=880|Color=8388608|FontID=2|IsHidden=T|Text=TAIYO YUDEN|Name=MFG NAME
|RECORD=41|OwnerIndex=369|IndexInSheet=1|OwnerPartId=-1|Location.X=610|Location.Y=880|Color=8388608|FontID=2|IsHidden=T|Text=TMK212BBJ106KG-T|Name=MFG PART NUM
|RECORD=41|OwnerIndex=369|IndexInSheet=2|OwnerPartId=-1|Location.X=610|Location.Y=880|Color=8388608|FontID=2|IsHidden=T|Text=10/23/2013|Name=MODIFY DATE
|RECORD=41|OwnerIndex=369|IndexInSheet=3|OwnerPartId=-1|Location.X=610|Location.Y=880|Color=8388608|FontID=2|IsHidden=T|Text=CAP, CER|Name=CATEGORY
|RECORD=41|OwnerIndex=369|IndexInSheet=4|OwnerPartId=-1|Location.X=608|Location.Y=892|Location.Y_Frac=50000|Color=8388608|FontID=2|IsHidden=T|Text=4/11/2006 3:37:28 PM|Name=Date
|RECORD=41|OwnerIndex=369|IndexInSheet=5|OwnerPartId=-1|Location.X=616|Location.Y=954|Location.Y_Frac=48252|Color=8388608|FontID=2|IsHidden=T|Text=*|Name=SHEETPART
|RECORD=41|OwnerIndex=369|IndexInSheet=6|OwnerPartId=-1|Location.X=616|Location.Y=954|Location.Y_Frac=48252|Color=8388608|FontID=2|IsHidden=T|Text=10%|Name=P1
|RECORD=41|OwnerIndex=369|IndexInSheet=7|OwnerPartId=-1|Location.X=616|Location.Y=954|Location.Y_Frac=48252|Color=8388608|FontID=2|IsHidden=T|Text=85C|Name=MAXTEMP
|RECORD=41|OwnerIndex=369|IndexInSheet=8|OwnerPartId=-1|Location.X=616|Location.Y=954|Location.Y_Frac=48252|Color=8388608|FontID=2|IsHidden=T|Text=-55C|Name=MINTEMP
|RECORD=41|OwnerIndex=369|IndexInSheet=9|OwnerPartId=-1|Location.X=616|Location.Y=954|Location.Y_Frac=48252|Color=8388608|FontID=2|IsHidden=T|Name=OTHER
|RECORD=41|OwnerIndex=369|IndexInSheet=10|OwnerPartId=-1|Location.X=616|Location.Y=954|Location.Y_Frac=48252|Color=8388608|FontID=2|IsHidden=T|Text=25V|Name=P2
|RECORD=41|OwnerIndex=369|IndexInSheet=11|OwnerPartId=-1|Location.X=616|Location.Y=954|Location.Y_Frac=48252|Color=8388608|FontID=2|IsHidden=T|Text=X5R|Name=P3
|RECORD=41|OwnerIndex=369|IndexInSheet=12|OwnerPartId=-1|Location.X=616|Location.Y=954|Location.Y_Frac=48252|Color=8388608|FontID=2|IsHidden=T|Text=0805|Name=Size
|RECORD=41|OwnerIndex=369|IndexInSheet=13|OwnerPartId=-1|Location.X=616|Location.Y=954|Location.Y_Frac=48252|Color=8388608|FontID=2|IsHidden=T|Name=SUB
|RECORD=41|OwnerIndex=369|IndexInSheet=14|OwnerPartId=-1|Location.X=616|Location.Y=954|Location.Y_Frac=48252|Color=8388608|FontID=1|IsHidden=T|Text=CAP, CER, 10.UF, 10V, 10%, X5R, 0805|Name=DESC
|RECORD=41|OwnerIndex=369|IndexInSheet=15|OwnerPartId=-1|Location.X=616|Location.Y=953|Location.Y_Frac=98252|Color=8388608|FontID=1|IsHidden=T|Text=MOUSER|Name=Supplier 1|ReadOnlyState=1
|RECORD=41|OwnerIndex=369|IndexInSheet=16|OwnerPartId=-1|Location.X=616|Location.Y=953|Location.Y_Frac=98252|Color=8388608|FontID=1|IsHidden=T|Text=963-TMK212BBJ106KG-T|Name=Supplier Part Number 1|ReadOnlyState=1
|RECORD=41|OwnerIndex=369|IndexInSheet=17|OwnerPartId=-1|Location.X=640|Location.Y=910|Color=8388608|FontID=2|Text=10uF|Name=VALUE
|RECORD=2|OwnerIndex=369|OwnerPartId=1|FormalType=1|Electrical=4|PinConglomerate=35|PinLength=10|Location.X=630|Location.Y=910|Name=2|Designator=2|SwapIdPin=2|SwapIDPart=1|PinPropagationDelay=0.000000E+000
|RECORD=2|OwnerIndex=369|OwnerPartId=1|FormalType=1|Electrical=4|PinConglomerate=33|PinLength=10|Location.X=630|Location.Y=920|Name=1|Designator=1|SwapIdPin=1|SwapIDPart=1|PinPropagationDelay=0.000000E+000
|RECORD=13|OwnerIndex=369|IsNotAccesible=T|IndexInSheet=20|OwnerPartId=1|Location.X=630|Location.Y=912|Location.Y_Frac=50000|Corner.X=630|Corner.Y=910|LineWidth=1|Color=16711680
|RECORD=13|OwnerIndex=369|IsNotAccesible=T|IndexInSheet=21|OwnerPartId=1|Location.X=630|Location.Y=920|Corner.X=630|Corner.Y=917|Corner.Y_Frac=50000|LineWidth=1|Color=16711680
|RECORD=13|OwnerIndex=369|IsNotAccesible=T|IndexInSheet=22|OwnerPartId=1|Location.X=635|Location.Y=912|Location.Y_Frac=50000|Corner.X=625|Corner.Y=912|Corner.Y_Frac=50000|LineWidth=1|Color=16711680
|RECORD=13|OwnerIndex=369|IsNotAccesible=T|IndexInSheet=23|OwnerPartId=1|Location.X=635|Location.Y=917|Location.Y_Frac=50000|Corner.X=625|Corner.Y=917|Corner.Y_Frac=50000|LineWidth=1|Color=16711680
|RECORD=41|OwnerIndex=369|IndexInSheet=24|OwnerPartId=-1|Location.X=616|Location.Y=953|Location.Y_Frac=98951|Color=8388608|FontID=1|IsHidden=T|Text=<VALENTIUM>|Name=VALENTIUM PART NUM
|RECORD=34|OwnerIndex=369|IndexInSheet=-1|OwnerPartId=-1|Location.X=640|Location.Y=920|Color=8388608|FontID=3|Text=C1|Name=Designator|ReadOnlyState=1
|RECORD=41|OwnerIndex=369|IndexInSheet=-1|OwnerPartId=-1|Location.X=637|Location.X_Frac=50000|Location.Y=875|Color=8388608|FontID=2|IsHidden=T|Text=CAP_0805_10UF_25V|Name=Comment
|RECORD=44|OwnerIndex=369
|RECORD=45|OwnerIndex=399|IndexInSheet=-1|Description=Chip Capacitor, 0805, 2-Leads, Body 2.00x1.25mm, IPC Medium Density|UseComponentLibrary=T|ModelName=CAPC2012X14N|ModelType=PCBLIB|DatafileCount=1|ModelDatafileEntity0=CAPC2012X14N|ModelDatafileKind0=PCBLib|IsCurrent=T|DatalinksLocked=T|DatabaseDatalinksLocked=T|IntegratedModel=T|DatabaseModel=T
|RECORD=46|OwnerIndex=400
|RECORD=48|OwnerIndex=400
|RECORD=1|LibReference=CAP_0805_10UF_25V|ComponentDescription=CAP, CER, 10.UF, 25V, 10%, X5R, 0805|PartCount=2|DisplayModeCount=1|IndexInSheet=55|OwnerPartId=-1|Location.X=30|Location.Y=480|CurrentPartId=1|LibraryPath=*|SourceLibraryName=Capacitors.IntLib|TargetFileName=*|AreaColor=11599871|Color=128|PartIDLocked=F|DesignItemId=CAP_0805_10UF_25V|AllPinCount=2
|RECORD=41|OwnerIndex=403|OwnerPartId=-1|Location.X=30|Location.Y=480|Color=8388608|FontID=2|IsHidden=T|Text=TAIYO YUDEN|Name=MFG NAME
|RECORD=41|OwnerIndex=403|IndexInSheet=1|OwnerPartId=-1|Location.X=30|Location.Y=480|Color=8388608|FontID=2|IsHidden=T|Text=TMK212BBJ106KG-T|Name=MFG PART NUM
|RECORD=41|OwnerIndex=403|IndexInSheet=2|OwnerPartId=-1|Location.X=30|Location.Y=480|Color=8388608|FontID=2|IsHidden=T|Text=10/23/2013|Name=MODIFY DATE
|RECORD=41|OwnerIndex=403|IndexInSheet=3|OwnerPartId=-1|Location.X=30|Location.Y=480|Color=8388608|FontID=2|IsHidden=T|Text=CAP, CER|Name=CATEGORY
|RECORD=41|OwnerIndex=403|IndexInSheet=4|OwnerPartId=-1|Location.X=28|Location.Y=492|Location.Y_Frac=50000|Color=8388608|FontID=2|IsHidden=T|Text=4/11/2006 3:37:28 PM|Name=Date
|RECORD=41|OwnerIndex=403|IndexInSheet=5|OwnerPartId=-1|Location.X=36|Location.Y=554|Location.Y_Frac=48252|Color=8388608|FontID=2|IsHidden=T|Text=*|Name=SHEETPART
|RECORD=41|OwnerIndex=403|IndexInSheet=6|OwnerPartId=-1|Location.X=36|Location.Y=554|Location.Y_Frac=48252|Color=8388608|FontID=2|IsHidden=T|Text=10%|Name=P1
|RECORD=41|OwnerIndex=403|IndexInSheet=7|OwnerPartId=-1|Location.X=36|Location.Y=554|Location.Y_Frac=48252|Color=8388608|FontID=2|IsHidden=T|Text=85C|Name=MAXTEMP
|RECORD=41|OwnerIndex=403|IndexInSheet=8|OwnerPartId=-1|Location.X=36|Location.Y=554|Location.Y_Frac=48252|Color=8388608|FontID=2|IsHidden=T|Text=-55C|Name=MINTEMP
|RECORD=41|OwnerIndex=403|IndexInSheet=9|OwnerPartId=-1|Location.X=36|Location.Y=554|Location.Y_Frac=48252|Color=8388608|FontID=2|IsHidden=T|Name=OTHER
|RECORD=41|OwnerIndex=403|IndexInSheet=10|OwnerPartId=-1|Location.X=36|Location.Y=554|Location.Y_Frac=48252|Color=8388608|FontID=2|IsHidden=T|Text=25V|Name=P2
|RECORD=41|OwnerIndex=403|IndexInSheet=11|OwnerPartId=-1|Location.X=36|Location.Y=554|Location.Y_Frac=48252|Color=8388608|FontID=2|IsHidden=T|Text=X5R|Name=P3
|RECORD=41|OwnerIndex=403|IndexInSheet=12|OwnerPartId=-1|Location.X=36|Location.Y=554|Location.Y_Frac=48252|Color=8388608|FontID=2|IsHidden=T|Text=0805|Name=Size
|RECORD=41|OwnerIndex=403|IndexInSheet=13|OwnerPartId=-1|Location.X=36|Location.Y=554|Location.Y_Frac=48252|Color=8388608|FontID=2|IsHidden=T|Name=SUB
|RECORD=41|OwnerIndex=403|IndexInSheet=14|OwnerPartId=-1|Location.X=36|Location.Y=554|Location.Y_Frac=48252|Color=8388608|FontID=1|IsHidden=T|Text=CAP, CER, 10.UF, 10V, 10%, X5R, 0805|Name=DESC
|RECORD=41|OwnerIndex=403|IndexInSheet=15|OwnerPartId=-1|Location.X=36|Location.Y=553|Location.Y_Frac=98252|Color=8388608|FontID=1|IsHidden=T|Text=MOUSER|Name=Supplier 1|ReadOnlyState=1
|RECORD=41|OwnerIndex=403|IndexInSheet=16|OwnerPartId=-1|Location.X=36|Location.Y=553|Location.Y_Frac=98252|Color=8388608|FontID=1|IsHidden=T|Text=963-TMK212BBJ106KG-T|Name=Supplier Part Number 1|ReadOnlyState=1
|RECORD=41|OwnerIndex=403|IndexInSheet=17|OwnerPartId=-1|Location.X=60|Location.Y=510|Color=8388608|FontID=2|Text=10uF|Name=VALUE
|RECORD=2|OwnerIndex=403|OwnerPartId=1|FormalType=1|Electrical=4|PinConglomerate=35|PinLength=10|Location.X=50|Location.Y=510|Name=2|Designator=2|SwapIdPin=2|SwapIDPart=1|PinPropagationDelay=0.000000E+000
|RECORD=2|OwnerIndex=403|OwnerPartId=1|FormalType=1|Electrical=4|PinConglomerate=33|PinLength=10|Location.X=50|Location.Y=520|Name=1|Designator=1|SwapIdPin=1|SwapIDPart=1|PinPropagationDelay=0.000000E+000
|RECORD=13|OwnerIndex=403|IsNotAccesible=T|IndexInSheet=20|OwnerPartId=1|Location.X=50|Location.Y=512|Location.Y_Frac=50000|Corner.X=50|Corner.Y=510|LineWidth=1|Color=16711680
|RECORD=13|OwnerIndex=403|IsNotAccesible=T|IndexInSheet=21|OwnerPartId=1|Location.X=50|Location.Y=520|Corner.X=50|Corner.Y=517|Corner.Y_Frac=50000|LineWidth=1|Color=16711680
|RECORD=13|OwnerIndex=403|IsNotAccesible=T|IndexInSheet=22|OwnerPartId=1|Location.X=55|Location.Y=512|Location.Y_Frac=50000|Corner.X=45|Corner.Y=512|Corner.Y_Frac=50000|LineWidth=1|Color=16711680
|RECORD=13|OwnerIndex=403|IsNotAccesible=T|IndexInSheet=23|OwnerPartId=1|Location.X=55|Location.Y=517|Location.Y_Frac=50000|Corner.X=45|Corner.Y=517|Corner.Y_Frac=50000|LineWidth=1|Color=16711680
|RECORD=41|OwnerIndex=403|IndexInSheet=24|OwnerPartId=-1|Location.X=36|Location.Y=553|Location.Y_Frac=98951|Color=8388608|FontID=1|IsHidden=T|Text=<VALENTIUM>|Name=VALENTIUM PART NUM
|RECORD=34|OwnerIndex=403|IndexInSheet=-1|OwnerPartId=-1|Location.X=60|Location.Y=520|Color=8388608|FontID=3|Text=C6|Name=Designator|ReadOnlyState=1
|RECORD=41|OwnerIndex=403|IndexInSheet=-1|OwnerPartId=-1|Location.X=57|Location.X_Frac=50000|Location.Y=475|Color=8388608|FontID=2|IsHidden=T|Text=CAP_0805_10UF_25V|Name=Comment
|RECORD=44|OwnerIndex=403
|RECORD=45|OwnerIndex=433|IndexInSheet=-1|Description=Chip Capacitor, 0805, 2-Leads, Body 2.00x1.25mm, IPC Medium Density|UseComponentLibrary=T|ModelName=CAPC2012X14N|ModelType=PCBLIB|DatafileCount=1|ModelDatafileEntity0=CAPC2012X14N|ModelDatafileKind0=PCBLib|IsCurrent=T|DatalinksLocked=T|DatabaseDatalinksLocked=T|IntegratedModel=T|DatabaseModel=T
|RECORD=46|OwnerIndex=434
|RECORD=48|OwnerIndex=434
|RECORD=1|LibReference=CAP_0805_10UF_25V|ComponentDescription=CAP, CER, 10.UF, 25V, 10%, X5R, 0805|PartCount=2|DisplayModeCount=1|IndexInSheet=56|OwnerPartId=-1|Location.X=530|Location.Y=350|CurrentPartId=1|LibraryPath=*|SourceLibraryName=Capacitors.IntLib|TargetFileName=*|AreaColor=11599871|Color=128|PartIDLocked=F|DesignItemId=CAP_0805_10UF_25V|AllPinCount=2
|RECORD=41|OwnerIndex=437|OwnerPartId=-1|Location.X=530|Location.Y=350|Color=8388608|FontID=2|IsHidden=T|Text=TAIYO YUDEN|Name=MFG NAME
|RECORD=41|OwnerIndex=437|IndexInSheet=1|OwnerPartId=-1|Location.X=530|Location.Y=350|Color=8388608|FontID=2|IsHidden=T|Text=TMK212BBJ106KG-T|Name=MFG PART NUM
|RECORD=41|OwnerIndex=437|IndexInSheet=2|OwnerPartId=-1|Location.X=530|Location.Y=350|Color=8388608|FontID=2|IsHidden=T|Text=10/23/2013|Name=MODIFY DATE
|RECORD=41|OwnerIndex=437|IndexInSheet=3|OwnerPartId=-1|Location.X=530|Location.Y=350|Color=8388608|FontID=2|IsHidden=T|Text=CAP, CER|Name=CATEGORY
|RECORD=41|OwnerIndex=437|IndexInSheet=4|OwnerPartId=-1|Location.X=528|Location.Y=362|Location.Y_Frac=50000|Color=8388608|FontID=2|IsHidden=T|Text=4/11/2006 3:37:28 PM|Name=Date
|RECORD=41|OwnerIndex=437|IndexInSheet=5|OwnerPartId=-1|Location.X=536|Location.Y=424|Location.Y_Frac=48252|Color=8388608|FontID=2|IsHidden=T|Text=*|Name=SHEETPART
|RECORD=41|OwnerIndex=437|IndexInSheet=6|OwnerPartId=-1|Location.X=536|Location.Y=424|Location.Y_Frac=48252|Color=8388608|FontID=2|IsHidden=T|Text=10%|Name=P1
|RECORD=41|OwnerIndex=437|IndexInSheet=7|OwnerPartId=-1|Location.X=536|Location.Y=424|Location.Y_Frac=48252|Color=8388608|FontID=2|IsHidden=T|Text=85C|Name=MAXTEMP
|RECORD=41|OwnerIndex=437|IndexInSheet=8|OwnerPartId=-1|Location.X=536|Location.Y=424|Location.Y_Frac=48252|Color=8388608|FontID=2|IsHidden=T|Text=-55C|Name=MINTEMP
|RECORD=41|OwnerIndex=437|IndexInSheet=9|OwnerPartId=-1|Location.X=536|Location.Y=424|Location.Y_Frac=48252|Color=8388608|FontID=2|IsHidden=T|Name=OTHER
|RECORD=41|OwnerIndex=437|IndexInSheet=10|OwnerPartId=-1|Location.X=536|Location.Y=424|Location.Y_Frac=48252|Color=8388608|FontID=2|IsHidden=T|Text=25V|Name=P2
|RECORD=41|OwnerIndex=437|IndexInSheet=11|OwnerPartId=-1|Location.X=536|Location.Y=424|Location.Y_Frac=48252|Color=8388608|FontID=2|IsHidden=T|Text=X5R|Name=P3
|RECORD=41|OwnerIndex=437|IndexInSheet=12|OwnerPartId=-1|Location.X=536|Location.Y=424|Location.Y_Frac=48252|Color=8388608|FontID=2|IsHidden=T|Text=0805|Name=Size
|RECORD=41|OwnerIndex=437|IndexInSheet=13|OwnerPartId=-1|Location.X=536|Location.Y=424|Location.Y_Frac=48252|Color=8388608|FontID=2|IsHidden=T|Name=SUB
|RECORD=41|OwnerIndex=437|IndexInSheet=14|OwnerPartId=-1|Location.X=536|Location.Y=424|Location.Y_Frac=48252|Color=8388608|FontID=1|IsHidden=T|Text=CAP, CER, 10.UF, 10V, 10%, X5R, 0805|Name=DESC
|RECORD=41|OwnerIndex=437|IndexInSheet=15|OwnerPartId=-1|Location.X=536|Location.Y=423|Location.Y_Frac=98252|Color=8388608|FontID=1|IsHidden=T|Text=MOUSER|Name=Supplier 1|ReadOnlyState=1
|RECORD=41|OwnerIndex=437|IndexInSheet=16|OwnerPartId=-1|Location.X=536|Location.Y=423|Location.Y_Frac=98252|Color=8388608|FontID=1|IsHidden=T|Text=963-TMK212BBJ106KG-T|Name=Supplier Part Number 1|ReadOnlyState=1
|RECORD=41|OwnerIndex=437|IndexInSheet=17|OwnerPartId=-1|Location.X=560|Location.Y=380|Color=8388608|FontID=2|Text=10uF|Name=VALUE
|RECORD=2|OwnerIndex=437|OwnerPartId=1|FormalType=1|Electrical=4|PinConglomerate=35|PinLength=10|Location.X=550|Location.Y=380|Name=2|Designator=2|SwapIdPin=2|SwapIDPart=1|PinPropagationDelay=0.000000E+000
|RECORD=2|OwnerIndex=437|OwnerPartId=1|FormalType=1|Electrical=4|PinConglomerate=33|PinLength=10|Location.X=550|Location.Y=390|Name=1|Designator=1|SwapIdPin=1|SwapIDPart=1|PinPropagationDelay=0.000000E+000
|RECORD=13|OwnerIndex=437|IsNotAccesible=T|IndexInSheet=20|OwnerPartId=1|Location.X=550|Location.Y=382|Location.Y_Frac=50000|Corner.X=550|Corner.Y=380|LineWidth=1|Color=16711680
|RECORD=13|OwnerIndex=437|IsNotAccesible=T|IndexInSheet=21|OwnerPartId=1|Location.X=550|Location.Y=390|Corner.X=550|Corner.Y=387|Corner.Y_Frac=50000|LineWidth=1|Color=16711680
|RECORD=13|OwnerIndex=437|IsNotAccesible=T|IndexInSheet=22|OwnerPartId=1|Location.X=555|Location.Y=382|Location.Y_Frac=50000|Corner.X=545|Corner.Y=382|Corner.Y_Frac=50000|LineWidth=1|Color=16711680
|RECORD=13|OwnerIndex=437|IsNotAccesible=T|IndexInSheet=23|OwnerPartId=1|Location.X=555|Location.Y=387|Location.Y_Frac=50000|Corner.X=545|Corner.Y=387|Corner.Y_Frac=50000|LineWidth=1|Color=16711680
|RECORD=41|OwnerIndex=437|IndexInSheet=24|OwnerPartId=-1|Location.X=536|Location.Y=423|Location.Y_Frac=98951|Color=8388608|FontID=1|IsHidden=T|Text=<VALENTIUM>|Name=VALENTIUM PART NUM
|RECORD=34|OwnerIndex=437|IndexInSheet=-1|OwnerPartId=-1|Location.X=560|Location.Y=390|Color=8388608|FontID=3|Text=C14|Name=Designator|ReadOnlyState=1
|RECORD=41|OwnerIndex=437|IndexInSheet=-1|OwnerPartId=-1|Location.X=557|Location.X_Frac=50000|Location.Y=345|Color=8388608|FontID=2|IsHidden=T|Text=CAP_0805_10UF_25V|Name=Comment
|RECORD=44|OwnerIndex=437
|RECORD=45|OwnerIndex=467|IndexInSheet=-1|Description=Chip Capacitor, 0805, 2-Leads, Body 2.00x1.25mm, IPC Medium Density|UseComponentLibrary=T|ModelName=CAPC2012X14N|ModelType=PCBLIB|DatafileCount=1|ModelDatafileEntity0=CAPC2012X14N|ModelDatafileKind0=PCBLib|IsCurrent=T|DatalinksLocked=T|DatabaseDatalinksLocked=T|IntegratedModel=T|DatabaseModel=T
|RECORD=46|OwnerIndex=468
|RECORD=48|OwnerIndex=468
|RECORD=1|LibReference=CAP_0805_10UF_25V|ComponentDescription=CAP, CER, 10.UF, 25V, 10%, X5R, 0805|PartCount=2|DisplayModeCount=1|IndexInSheet=57|OwnerPartId=-1|Location.X=480|Location.Y=350|CurrentPartId=1|LibraryPath=*|SourceLibraryName=Capacitors.IntLib|TargetFileName=*|AreaColor=11599871|Color=128|PartIDLocked=F|DesignItemId=CAP_0805_10UF_25V|AllPinCount=2
|RECORD=41|OwnerIndex=471|OwnerPartId=-1|Location.X=480|Location.Y=350|Color=8388608|FontID=2|IsHidden=T|Text=TAIYO YUDEN|Name=MFG NAME
|RECORD=41|OwnerIndex=471|IndexInSheet=1|OwnerPartId=-1|Location.X=480|Location.Y=350|Color=8388608|FontID=2|IsHidden=T|Text=TMK212BBJ106KG-T|Name=MFG PART NUM
|RECORD=41|OwnerIndex=471|IndexInSheet=2|OwnerPartId=-1|Location.X=480|Location.Y=350|Color=8388608|FontID=2|IsHidden=T|Text=10/23/2013|Name=MODIFY DATE
|RECORD=41|OwnerIndex=471|IndexInSheet=3|OwnerPartId=-1|Location.X=480|Location.Y=350|Color=8388608|FontID=2|IsHidden=T|Text=CAP, CER|Name=CATEGORY
|RECORD=41|OwnerIndex=471|IndexInSheet=4|OwnerPartId=-1|Location.X=478|Location.Y=362|Location.Y_Frac=50000|Color=8388608|FontID=2|IsHidden=T|Text=4/11/2006 3:37:28 PM|Name=Date
|RECORD=41|OwnerIndex=471|IndexInSheet=5|OwnerPartId=-1|Location.X=486|Location.Y=424|Location.Y_Frac=48252|Color=8388608|FontID=2|IsHidden=T|Text=*|Name=SHEETPART
|RECORD=41|OwnerIndex=471|IndexInSheet=6|OwnerPartId=-1|Location.X=486|Location.Y=424|Location.Y_Frac=48252|Color=8388608|FontID=2|IsHidden=T|Text=10%|Name=P1
|RECORD=41|OwnerIndex=471|IndexInSheet=7|OwnerPartId=-1|Location.X=486|Location.Y=424|Location.Y_Frac=48252|Color=8388608|FontID=2|IsHidden=T|Text=85C|Name=MAXTEMP
|RECORD=41|OwnerIndex=471|IndexInSheet=8|OwnerPartId=-1|Location.X=486|Location.Y=424|Location.Y_Frac=48252|Color=8388608|FontID=2|IsHidden=T|Text=-55C|Name=MINTEMP
|RECORD=41|OwnerIndex=471|IndexInSheet=9|OwnerPartId=-1|Location.X=486|Location.Y=424|Location.Y_Frac=48252|Color=8388608|FontID=2|IsHidden=T|Name=OTHER
|RECORD=41|OwnerIndex=471|IndexInSheet=10|OwnerPartId=-1|Location.X=486|Location.Y=424|Location.Y_Frac=48252|Color=8388608|FontID=2|IsHidden=T|Text=25V|Name=P2
|RECORD=41|OwnerIndex=471|IndexInSheet=11|OwnerPartId=-1|Location.X=486|Location.Y=424|Location.Y_Frac=48252|Color=8388608|FontID=2|IsHidden=T|Text=X5R|Name=P3
|RECORD=41|OwnerIndex=471|IndexInSheet=12|OwnerPartId=-1|Location.X=486|Location.Y=424|Location.Y_Frac=48252|Color=8388608|FontID=2|IsHidden=T|Text=0805|Name=Size
|RECORD=41|OwnerIndex=471|IndexInSheet=13|OwnerPartId=-1|Location.X=486|Location.Y=424|Location.Y_Frac=48252|Color=8388608|FontID=2|IsHidden=T|Name=SUB
|RECORD=41|OwnerIndex=471|IndexInSheet=14|OwnerPartId=-1|Location.X=486|Location.Y=424|Location.Y_Frac=48252|Color=8388608|FontID=1|IsHidden=T|Text=CAP, CER, 10.UF, 10V, 10%, X5R, 0805|Name=DESC
|RECORD=41|OwnerIndex=471|IndexInSheet=15|OwnerPartId=-1|Location.X=486|Location.Y=423|Location.Y_Frac=98252|Color=8388608|FontID=1|IsHidden=T|Text=MOUSER|Name=Supplier 1|ReadOnlyState=1
|RECORD=41|OwnerIndex=471|IndexInSheet=16|OwnerPartId=-1|Location.X=486|Location.Y=423|Location.Y_Frac=98252|Color=8388608|FontID=1|IsHidden=T|Text=963-TMK212BBJ106KG-T|Name=Supplier Part Number 1|ReadOnlyState=1
|RECORD=41|OwnerIndex=471|IndexInSheet=17|OwnerPartId=-1|Location.X=510|Location.Y=380|Color=8388608|FontID=2|Text=10uF|Name=VALUE
|RECORD=2|OwnerIndex=471|OwnerPartId=1|FormalType=1|Electrical=4|PinConglomerate=35|PinLength=10|Location.X=500|Location.Y=380|Name=2|Designator=2|SwapIdPin=2|SwapIDPart=1|PinPropagationDelay=0.000000E+000
|RECORD=2|OwnerIndex=471|OwnerPartId=1|FormalType=1|Electrical=4|PinConglomerate=33|PinLength=10|Location.X=500|Location.Y=390|Name=1|Designator=1|SwapIdPin=1|SwapIDPart=1|PinPropagationDelay=0.000000E+000
|RECORD=13|OwnerIndex=471|IsNotAccesible=T|IndexInSheet=20|OwnerPartId=1|Location.X=500|Location.Y=382|Location.Y_Frac=50000|Corner.X=500|Corner.Y=380|LineWidth=1|Color=16711680
|RECORD=13|OwnerIndex=471|IsNotAccesible=T|IndexInSheet=21|OwnerPartId=1|Location.X=500|Location.Y=390|Corner.X=500|Corner.Y=387|Corner.Y_Frac=50000|LineWidth=1|Color=16711680
|RECORD=13|OwnerIndex=471|IsNotAccesible=T|IndexInSheet=22|OwnerPartId=1|Location.X=505|Location.Y=382|Location.Y_Frac=50000|Corner.X=495|Corner.Y=382|Corner.Y_Frac=50000|LineWidth=1|Color=16711680
|RECORD=13|OwnerIndex=471|IsNotAccesible=T|IndexInSheet=23|OwnerPartId=1|Location.X=505|Location.Y=387|Location.Y_Frac=50000|Corner.X=495|Corner.Y=387|Corner.Y_Frac=50000|LineWidth=1|Color=16711680
|RECORD=41|OwnerIndex=471|IndexInSheet=24|OwnerPartId=-1|Location.X=486|Location.Y=423|Location.Y_Frac=98951|Color=8388608|FontID=1|IsHidden=T|Text=<VALENTIUM>|Name=VALENTIUM PART NUM
|RECORD=34|OwnerIndex=471|IndexInSheet=-1|OwnerPartId=-1|Location.X=510|Location.Y=390|Color=8388608|FontID=3|Text=C13|Name=Designator|ReadOnlyState=1
|RECORD=41|OwnerIndex=471|IndexInSheet=-1|OwnerPartId=-1|Location.X=507|Location.X_Frac=50000|Location.Y=345|Color=8388608|FontID=2|IsHidden=T|Text=CAP_0805_10UF_25V|Name=Comment
|RECORD=44|OwnerIndex=471
|RECORD=45|OwnerIndex=501|IndexInSheet=-1|Description=Chip Capacitor, 0805, 2-Leads, Body 2.00x1.25mm, IPC Medium Density|UseComponentLibrary=T|ModelName=CAPC2012X14N|ModelType=PCBLIB|DatafileCount=1|ModelDatafileEntity0=CAPC2012X14N|ModelDatafileKind0=PCBLib|IsCurrent=T|DatalinksLocked=T|DatabaseDatalinksLocked=T|IntegratedModel=T|DatabaseModel=T
|RECORD=46|OwnerIndex=502
|RECORD=48|OwnerIndex=502
|RECORD=1|LibReference=CAP_0805_10UF_25V|ComponentDescription=CAP, CER, 10.UF, 25V, 10%, X5R, 0805|PartCount=2|DisplayModeCount=1|IndexInSheet=58|OwnerPartId=-1|Location.X=800|Location.Y=490|CurrentPartId=1|LibraryPath=*|SourceLibraryName=Capacitors.IntLib|TargetFileName=*|AreaColor=11599871|Color=128|PartIDLocked=F|DesignItemId=CAP_0805_10UF_25V|AllPinCount=2
|RECORD=41|OwnerIndex=505|OwnerPartId=-1|Location.X=800|Location.Y=490|Color=8388608|FontID=2|IsHidden=T|Text=TAIYO YUDEN|Name=MFG NAME
|RECORD=41|OwnerIndex=505|IndexInSheet=1|OwnerPartId=-1|Location.X=800|Location.Y=490|Color=8388608|FontID=2|IsHidden=T|Text=TMK212BBJ106KG-T|Name=MFG PART NUM
|RECORD=41|OwnerIndex=505|IndexInSheet=2|OwnerPartId=-1|Location.X=800|Location.Y=490|Color=8388608|FontID=2|IsHidden=T|Text=10/23/2013|Name=MODIFY DATE
|RECORD=41|OwnerIndex=505|IndexInSheet=3|OwnerPartId=-1|Location.X=800|Location.Y=490|Color=8388608|FontID=2|IsHidden=T|Text=CAP, CER|Name=CATEGORY
|RECORD=41|OwnerIndex=505|IndexInSheet=4|OwnerPartId=-1|Location.X=798|Location.Y=502|Location.Y_Frac=50000|Color=8388608|FontID=2|IsHidden=T|Text=4/11/2006 3:37:28 PM|Name=Date
|RECORD=41|OwnerIndex=505|IndexInSheet=5|OwnerPartId=-1|Location.X=806|Location.Y=564|Location.Y_Frac=48252|Color=8388608|FontID=2|IsHidden=T|Text=*|Name=SHEETPART
|RECORD=41|OwnerIndex=505|IndexInSheet=6|OwnerPartId=-1|Location.X=806|Location.Y=564|Location.Y_Frac=48252|Color=8388608|FontID=2|IsHidden=T|Text=10%|Name=P1
|RECORD=41|OwnerIndex=505|IndexInSheet=7|OwnerPartId=-1|Location.X=806|Location.Y=564|Location.Y_Frac=48252|Color=8388608|FontID=2|IsHidden=T|Text=85C|Name=MAXTEMP
|RECORD=41|OwnerIndex=505|IndexInSheet=8|OwnerPartId=-1|Location.X=806|Location.Y=564|Location.Y_Frac=48252|Color=8388608|FontID=2|IsHidden=T|Text=-55C|Name=MINTEMP
|RECORD=41|OwnerIndex=505|IndexInSheet=9|OwnerPartId=-1|Location.X=806|Location.Y=564|Location.Y_Frac=48252|Color=8388608|FontID=2|IsHidden=T|Name=OTHER
|RECORD=41|OwnerIndex=505|IndexInSheet=10|OwnerPartId=-1|Location.X=806|Location.Y=564|Location.Y_Frac=48252|Color=8388608|FontID=2|IsHidden=T|Text=25V|Name=P2
|RECORD=41|OwnerIndex=505|IndexInSheet=11|OwnerPartId=-1|Location.X=806|Location.Y=564|Location.Y_Frac=48252|Color=8388608|FontID=2|IsHidden=T|Text=X5R|Name=P3
|RECORD=41|OwnerIndex=505|IndexInSheet=12|OwnerPartId=-1|Location.X=806|Location.Y=564|Location.Y_Frac=48252|Color=8388608|FontID=2|IsHidden=T|Text=0805|Name=Size
|RECORD=41|OwnerIndex=505|IndexInSheet=13|OwnerPartId=-1|Location.X=806|Location.Y=564|Location.Y_Frac=48252|Color=8388608|FontID=2|IsHidden=T|Name=SUB
|RECORD=41|OwnerIndex=505|IndexInSheet=14|OwnerPartId=-1|Location.X=806|Location.Y=564|Location.Y_Frac=48252|Color=8388608|FontID=1|IsHidden=T|Text=CAP, CER, 10.UF, 10V, 10%, X5R, 0805|Name=DESC
|RECORD=41|OwnerIndex=505|IndexInSheet=15|OwnerPartId=-1|Location.X=806|Location.Y=563|Location.Y_Frac=98252|Color=8388608|FontID=1|IsHidden=T|Text=MOUSER|Name=Supplier 1|ReadOnlyState=1
|RECORD=41|OwnerIndex=505|IndexInSheet=16|OwnerPartId=-1|Location.X=806|Location.Y=563|Location.Y_Frac=98252|Color=8388608|FontID=1|IsHidden=T|Text=963-TMK212BBJ106KG-T|Name=Supplier Part Number 1|ReadOnlyState=1
|RECORD=41|OwnerIndex=505|IndexInSheet=17|OwnerPartId=-1|Location.X=830|Location.Y=520|Color=8388608|FontID=2|Text=10uF|Name=VALUE
|RECORD=2|OwnerIndex=505|OwnerPartId=1|FormalType=1|Electrical=4|PinConglomerate=35|PinLength=10|Location.X=820|Location.Y=520|Name=2|Designator=2|SwapIdPin=2|SwapIDPart=1|PinPropagationDelay=0.000000E+000
|RECORD=2|OwnerIndex=505|OwnerPartId=1|FormalType=1|Electrical=4|PinConglomerate=33|PinLength=10|Location.X=820|Location.Y=530|Name=1|Designator=1|SwapIdPin=1|SwapIDPart=1|PinPropagationDelay=0.000000E+000
|RECORD=13|OwnerIndex=505|IsNotAccesible=T|IndexInSheet=20|OwnerPartId=1|Location.X=820|Location.Y=522|Location.Y_Frac=50000|Corner.X=820|Corner.Y=520|LineWidth=1|Color=16711680
|RECORD=13|OwnerIndex=505|IsNotAccesible=T|IndexInSheet=21|OwnerPartId=1|Location.X=820|Location.Y=530|Corner.X=820|Corner.Y=527|Corner.Y_Frac=50000|LineWidth=1|Color=16711680
|RECORD=13|OwnerIndex=505|IsNotAccesible=T|IndexInSheet=22|OwnerPartId=1|Location.X=825|Location.Y=522|Location.Y_Frac=50000|Corner.X=815|Corner.Y=522|Corner.Y_Frac=50000|LineWidth=1|Color=16711680
|RECORD=13|OwnerIndex=505|IsNotAccesible=T|IndexInSheet=23|OwnerPartId=1|Location.X=825|Location.Y=527|Location.Y_Frac=50000|Corner.X=815|Corner.Y=527|Corner.Y_Frac=50000|LineWidth=1|Color=16711680
|RECORD=41|OwnerIndex=505|IndexInSheet=24|OwnerPartId=-1|Location.X=806|Location.Y=563|Location.Y_Frac=98951|Color=8388608|FontID=1|IsHidden=T|Text=<VALENTIUM>|Name=VALENTIUM PART NUM
|RECORD=34|OwnerIndex=505|IndexInSheet=-1|OwnerPartId=-1|Location.X=830|Location.Y=530|Color=8388608|FontID=3|Text=C5|Name=Designator|ReadOnlyState=1
|RECORD=41|OwnerIndex=505|IndexInSheet=-1|OwnerPartId=-1|Location.X=827|Location.X_Frac=50000|Location.Y=485|Color=8388608|FontID=2|IsHidden=T|Text=CAP_0805_10UF_25V|Name=Comment
|RECORD=44|OwnerIndex=505
|RECORD=45|OwnerIndex=535|IndexInSheet=-1|Description=Chip Capacitor, 0805, 2-Leads, Body 2.00x1.25mm, IPC Medium Density|UseComponentLibrary=T|ModelName=CAPC2012X14N|ModelType=PCBLIB|DatafileCount=1|ModelDatafileEntity0=CAPC2012X14N|ModelDatafileKind0=PCBLib|IsCurrent=T|DatalinksLocked=T|DatabaseDatalinksLocked=T|IntegratedModel=T|DatabaseModel=T
|RECORD=46|OwnerIndex=536
|RECORD=48|OwnerIndex=536
|RECORD=1|LibReference=CAP_0805_10UF_25V|ComponentDescription=CAP, CER, 10.UF, 25V, 10%, X5R, 0805|PartCount=2|DisplayModeCount=1|IndexInSheet=59|OwnerPartId=-1|Location.X=1240|Location.Y=360|CurrentPartId=1|LibraryPath=*|SourceLibraryName=Capacitors.IntLib|TargetFileName=*|AreaColor=11599871|Color=128|PartIDLocked=F|DesignItemId=CAP_0805_10UF_25V|AllPinCount=2
|RECORD=41|OwnerIndex=539|OwnerPartId=-1|Location.X=1240|Location.Y=360|Color=8388608|FontID=2|IsHidden=T|Text=TAIYO YUDEN|Name=MFG NAME
|RECORD=41|OwnerIndex=539|IndexInSheet=1|OwnerPartId=-1|Location.X=1240|Location.Y=360|Color=8388608|FontID=2|IsHidden=T|Text=TMK212BBJ106KG-T|Name=MFG PART NUM
|RECORD=41|OwnerIndex=539|IndexInSheet=2|OwnerPartId=-1|Location.X=1240|Location.Y=360|Color=8388608|FontID=2|IsHidden=T|Text=10/23/2013|Name=MODIFY DATE
|RECORD=41|OwnerIndex=539|IndexInSheet=3|OwnerPartId=-1|Location.X=1240|Location.Y=360|Color=8388608|FontID=2|IsHidden=T|Text=CAP, CER|Name=CATEGORY
|RECORD=41|OwnerIndex=539|IndexInSheet=4|OwnerPartId=-1|Location.X=1238|Location.Y=372|Location.Y_Frac=50000|Color=8388608|FontID=2|IsHidden=T|Text=4/11/2006 3:37:28 PM|Name=Date
|RECORD=41|OwnerIndex=539|IndexInSheet=5|OwnerPartId=-1|Location.X=1246|Location.Y=434|Location.Y_Frac=48252|Color=8388608|FontID=2|IsHidden=T|Text=*|Name=SHEETPART
|RECORD=41|OwnerIndex=539|IndexInSheet=6|OwnerPartId=-1|Location.X=1246|Location.Y=434|Location.Y_Frac=48252|Color=8388608|FontID=2|IsHidden=T|Text=10%|Name=P1
|RECORD=41|OwnerIndex=539|IndexInSheet=7|OwnerPartId=-1|Location.X=1246|Location.Y=434|Location.Y_Frac=48252|Color=8388608|FontID=2|IsHidden=T|Text=85C|Name=MAXTEMP
|RECORD=41|OwnerIndex=539|IndexInSheet=8|OwnerPartId=-1|Location.X=1246|Location.Y=434|Location.Y_Frac=48252|Color=8388608|FontID=2|IsHidden=T|Text=-55C|Name=MINTEMP
|RECORD=41|OwnerIndex=539|IndexInSheet=9|OwnerPartId=-1|Location.X=1246|Location.Y=434|Location.Y_Frac=48252|Color=8388608|FontID=2|IsHidden=T|Name=OTHER
|RECORD=41|OwnerIndex=539|IndexInSheet=10|OwnerPartId=-1|Location.X=1246|Location.Y=434|Location.Y_Frac=48252|Color=8388608|FontID=2|IsHidden=T|Text=25V|Name=P2
|RECORD=41|OwnerIndex=539|IndexInSheet=11|OwnerPartId=-1|Location.X=1246|Location.Y=434|Location.Y_Frac=48252|Color=8388608|FontID=2|IsHidden=T|Text=X5R|Name=P3
|RECORD=41|OwnerIndex=539|IndexInSheet=12|OwnerPartId=-1|Location.X=1246|Location.Y=434|Location.Y_Frac=48252|Color=8388608|FontID=2|IsHidden=T|Text=0805|Name=Size
|RECORD=41|OwnerIndex=539|IndexInSheet=13|OwnerPartId=-1|Location.X=1246|Location.Y=434|Location.Y_Frac=48252|Color=8388608|FontID=2|IsHidden=T|Name=SUB
|RECORD=41|OwnerIndex=539|IndexInSheet=14|OwnerPartId=-1|Location.X=1246|Location.Y=434|Location.Y_Frac=48252|Color=8388608|FontID=1|IsHidden=T|Text=CAP, CER, 10.UF, 10V, 10%, X5R, 0805|Name=DESC
|RECORD=41|OwnerIndex=539|IndexInSheet=15|OwnerPartId=-1|Location.X=1246|Location.Y=433|Location.Y_Frac=98252|Color=8388608|FontID=1|IsHidden=T|Text=MOUSER|Name=Supplier 1|ReadOnlyState=1
|RECORD=41|OwnerIndex=539|IndexInSheet=16|OwnerPartId=-1|Location.X=1246|Location.Y=433|Location.Y_Frac=98252|Color=8388608|FontID=1|IsHidden=T|Text=963-TMK212BBJ106KG-T|Name=Supplier Part Number 1|ReadOnlyState=1
|RECORD=41|OwnerIndex=539|IndexInSheet=17|OwnerPartId=-1|Location.X=1270|Location.Y=390|Color=8388608|FontID=2|Text=10uF|Name=VALUE
|RECORD=2|OwnerIndex=539|OwnerPartId=1|FormalType=1|Electrical=4|PinConglomerate=35|PinLength=10|Location.X=1260|Location.Y=390|Name=2|Designator=2|SwapIdPin=2|SwapIDPart=1|PinPropagationDelay=0.000000E+000
|RECORD=2|OwnerIndex=539|OwnerPartId=1|FormalType=1|Electrical=4|PinConglomerate=33|PinLength=10|Location.X=1260|Location.Y=400|Name=1|Designator=1|SwapIdPin=1|SwapIDPart=1|PinPropagationDelay=0.000000E+000
|RECORD=13|OwnerIndex=539|IsNotAccesible=T|IndexInSheet=20|OwnerPartId=1|Location.X=1260|Location.Y=392|Location.Y_Frac=50000|Corner.X=1260|Corner.Y=390|LineWidth=1|Color=16711680
|RECORD=13|OwnerIndex=539|IsNotAccesible=T|IndexInSheet=21|OwnerPartId=1|Location.X=1260|Location.Y=400|Corner.X=1260|Corner.Y=397|Corner.Y_Frac=50000|LineWidth=1|Color=16711680
|RECORD=13|OwnerIndex=539|IsNotAccesible=T|IndexInSheet=22|OwnerPartId=1|Location.X=1265|Location.Y=392|Location.Y_Frac=50000|Corner.X=1255|Corner.Y=392|Corner.Y_Frac=50000|LineWidth=1|Color=16711680
|RECORD=13|OwnerIndex=539|IsNotAccesible=T|IndexInSheet=23|OwnerPartId=1|Location.X=1265|Location.Y=397|Location.Y_Frac=50000|Corner.X=1255|Corner.Y=397|Corner.Y_Frac=50000|LineWidth=1|Color=16711680
|RECORD=41|OwnerIndex=539|IndexInSheet=24|OwnerPartId=-1|Location.X=1246|Location.Y=433|Location.Y_Frac=98951|Color=8388608|FontID=1|IsHidden=T|Text=<VALENTIUM>|Name=VALENTIUM PART NUM
|RECORD=34|OwnerIndex=539|IndexInSheet=-1|OwnerPartId=-1|Location.X=1270|Location.Y=400|Color=8388608|FontID=3|Text=C7|Name=Designator|ReadOnlyState=1
|RECORD=41|OwnerIndex=539|IndexInSheet=-1|OwnerPartId=-1|Location.X=1267|Location.X_Frac=50000|Location.Y=355|Color=8388608|FontID=2|IsHidden=T|Text=CAP_0805_10UF_25V|Name=Comment
|RECORD=44|OwnerIndex=539
|RECORD=45|OwnerIndex=569|IndexInSheet=-1|Description=Chip Capacitor, 0805, 2-Leads, Body 2.00x1.25mm, IPC Medium Density|UseComponentLibrary=T|ModelName=CAPC2012X14N|ModelType=PCBLIB|DatafileCount=1|ModelDatafileEntity0=CAPC2012X14N|ModelDatafileKind0=PCBLib|IsCurrent=T|DatalinksLocked=T|DatabaseDatalinksLocked=T|IntegratedModel=T|DatabaseModel=T
|RECORD=46|OwnerIndex=570
|RECORD=48|OwnerIndex=570
|RECORD=1|LibReference=CAP_0805_10UF_25V|ComponentDescription=CAP, CER, 10.UF, 25V, 10%, X5R, 0805|PartCount=2|DisplayModeCount=1|IndexInSheet=60|OwnerPartId=-1|Location.X=1290|Location.Y=360|CurrentPartId=1|LibraryPath=*|SourceLibraryName=Capacitors.IntLib|TargetFileName=*|AreaColor=11599871|Color=128|PartIDLocked=F|DesignItemId=CAP_0805_10UF_25V|AllPinCount=2
|RECORD=41|OwnerIndex=573|OwnerPartId=-1|Location.X=1290|Location.Y=360|Color=8388608|FontID=2|IsHidden=T|Text=TAIYO YUDEN|Name=MFG NAME
|RECORD=41|OwnerIndex=573|IndexInSheet=1|OwnerPartId=-1|Location.X=1290|Location.Y=360|Color=8388608|FontID=2|IsHidden=T|Text=TMK212BBJ106KG-T|Name=MFG PART NUM
|RECORD=41|OwnerIndex=573|IndexInSheet=2|OwnerPartId=-1|Location.X=1290|Location.Y=360|Color=8388608|FontID=2|IsHidden=T|Text=10/23/2013|Name=MODIFY DATE
|RECORD=41|OwnerIndex=573|IndexInSheet=3|OwnerPartId=-1|Location.X=1290|Location.Y=360|Color=8388608|FontID=2|IsHidden=T|Text=CAP, CER|Name=CATEGORY
|RECORD=41|OwnerIndex=573|IndexInSheet=4|OwnerPartId=-1|Location.X=1288|Location.Y=372|Location.Y_Frac=50000|Color=8388608|FontID=2|IsHidden=T|Text=4/11/2006 3:37:28 PM|Name=Date
|RECORD=41|OwnerIndex=573|IndexInSheet=5|OwnerPartId=-1|Location.X=1296|Location.Y=434|Location.Y_Frac=48252|Color=8388608|FontID=2|IsHidden=T|Text=*|Name=SHEETPART
|RECORD=41|OwnerIndex=573|IndexInSheet=6|OwnerPartId=-1|Location.X=1296|Location.Y=434|Location.Y_Frac=48252|Color=8388608|FontID=2|IsHidden=T|Text=10%|Name=P1
|RECORD=41|OwnerIndex=573|IndexInSheet=7|OwnerPartId=-1|Location.X=1296|Location.Y=434|Location.Y_Frac=48252|Color=8388608|FontID=2|IsHidden=T|Text=85C|Name=MAXTEMP
|RECORD=41|OwnerIndex=573|IndexInSheet=8|OwnerPartId=-1|Location.X=1296|Location.Y=434|Location.Y_Frac=48252|Color=8388608|FontID=2|IsHidden=T|Text=-55C|Name=MINTEMP
|RECORD=41|OwnerIndex=573|IndexInSheet=9|OwnerPartId=-1|Location.X=1296|Location.Y=434|Location.Y_Frac=48252|Color=8388608|FontID=2|IsHidden=T|Name=OTHER
|RECORD=41|OwnerIndex=573|IndexInSheet=10|OwnerPartId=-1|Location.X=1296|Location.Y=434|Location.Y_Frac=48252|Color=8388608|FontID=2|IsHidden=T|Text=25V|Name=P2
|RECORD=41|OwnerIndex=573|IndexInSheet=11|OwnerPartId=-1|Location.X=1296|Location.Y=434|Location.Y_Frac=48252|Color=8388608|FontID=2|IsHidden=T|Text=X5R|Name=P3
|RECORD=41|OwnerIndex=573|IndexInSheet=12|OwnerPartId=-1|Location.X=1296|Location.Y=434|Location.Y_Frac=48252|Color=8388608|FontID=2|IsHidden=T|Text=0805|Name=Size
|RECORD=41|OwnerIndex=573|IndexInSheet=13|OwnerPartId=-1|Location.X=1296|Location.Y=434|Location.Y_Frac=48252|Color=8388608|FontID=2|IsHidden=T|Name=SUB
|RECORD=41|OwnerIndex=573|IndexInSheet=14|OwnerPartId=-1|Location.X=1296|Location.Y=434|Location.Y_Frac=48252|Color=8388608|FontID=1|IsHidden=T|Text=CAP, CER, 10.UF, 10V, 10%, X5R, 0805|Name=DESC
|RECORD=41|OwnerIndex=573|IndexInSheet=15|OwnerPartId=-1|Location.X=1296|Location.Y=433|Location.Y_Frac=98252|Color=8388608|FontID=1|IsHidden=T|Text=MOUSER|Name=Supplier 1|ReadOnlyState=1
|RECORD=41|OwnerIndex=573|IndexInSheet=16|OwnerPartId=-1|Location.X=1296|Location.Y=433|Location.Y_Frac=98252|Color=8388608|FontID=1|IsHidden=T|Text=963-TMK212BBJ106KG-T|Name=Supplier Part Number 1|ReadOnlyState=1
|RECORD=41|OwnerIndex=573|IndexInSheet=17|OwnerPartId=-1|Location.X=1320|Location.Y=390|Color=8388608|FontID=2|Text=10uF|Name=VALUE
|RECORD=2|OwnerIndex=573|OwnerPartId=1|FormalType=1|Electrical=4|PinConglomerate=35|PinLength=10|Location.X=1310|Location.Y=390|Name=2|Designator=2|SwapIdPin=2|SwapIDPart=1|PinPropagationDelay=0.000000E+000
|RECORD=2|OwnerIndex=573|OwnerPartId=1|FormalType=1|Electrical=4|PinConglomerate=33|PinLength=10|Location.X=1310|Location.Y=400|Name=1|Designator=1|SwapIdPin=1|SwapIDPart=1|PinPropagationDelay=0.000000E+000
|RECORD=13|OwnerIndex=573|IsNotAccesible=T|IndexInSheet=20|OwnerPartId=1|Location.X=1310|Location.Y=392|Location.Y_Frac=50000|Corner.X=1310|Corner.Y=390|LineWidth=1|Color=16711680
|RECORD=13|OwnerIndex=573|IsNotAccesible=T|IndexInSheet=21|OwnerPartId=1|Location.X=1310|Location.Y=400|Corner.X=1310|Corner.Y=397|Corner.Y_Frac=50000|LineWidth=1|Color=16711680
|RECORD=13|OwnerIndex=573|IsNotAccesible=T|IndexInSheet=22|OwnerPartId=1|Location.X=1315|Location.Y=392|Location.Y_Frac=50000|Corner.X=1305|Corner.Y=392|Corner.Y_Frac=50000|LineWidth=1|Color=16711680
|RECORD=13|OwnerIndex=573|IsNotAccesible=T|IndexInSheet=23|OwnerPartId=1|Location.X=1315|Location.Y=397|Location.Y_Frac=50000|Corner.X=1305|Corner.Y=397|Corner.Y_Frac=50000|LineWidth=1|Color=16711680
|RECORD=41|OwnerIndex=573|IndexInSheet=24|OwnerPartId=-1|Location.X=1296|Location.Y=433|Location.Y_Frac=98951|Color=8388608|FontID=1|IsHidden=T|Text=<VALENTIUM>|Name=VALENTIUM PART NUM
|RECORD=34|OwnerIndex=573|IndexInSheet=-1|OwnerPartId=-1|Location.X=1320|Location.Y=400|Color=8388608|FontID=3|Text=C8|Name=Designator|ReadOnlyState=1
|RECORD=41|OwnerIndex=573|IndexInSheet=-1|OwnerPartId=-1|Location.X=1317|Location.X_Frac=50000|Location.Y=355|Color=8388608|FontID=2|IsHidden=T|Text=CAP_0805_10UF_25V|Name=Comment
|RECORD=44|OwnerIndex=573
|RECORD=45|OwnerIndex=603|IndexInSheet=-1|Description=Chip Capacitor, 0805, 2-Leads, Body 2.00x1.25mm, IPC Medium Density|UseComponentLibrary=T|ModelName=CAPC2012X14N|ModelType=PCBLIB|DatafileCount=1|ModelDatafileEntity0=CAPC2012X14N|ModelDatafileKind0=PCBLib|IsCurrent=T|DatalinksLocked=T|DatabaseDatalinksLocked=T|IntegratedModel=T|DatabaseModel=T
|RECORD=46|OwnerIndex=604
|RECORD=48|OwnerIndex=604
|RECORD=1|LibReference=SMTLED_RED_0603_SML|ComponentDescription=LED, RED, SML-LX0603, 635NM, 2V, 20MA, 0603|PartCount=2|DisplayModeCount=1|IndexInSheet=61|OwnerPartId=-1|Location.X=1620|Location.Y=430|Orientation=3|CurrentPartId=1|LibraryPath=*|SourceLibraryName=Passives.IntLib|TargetFileName=*|AreaColor=11599871|Color=128|PartIDLocked=F|DesignItemId=SMTLED_RED_0603_SML|AllPinCount=2
|RECORD=41|OwnerIndex=607|OwnerPartId=-1|Location.X=1607|Location.X_Frac=50000|Location.Y=432|Color=8388608|FontID=2|IsHidden=T|Text=SML-LX0603IW-TR|Name=MFG PART NUM
|RECORD=41|OwnerIndex=607|IndexInSheet=1|OwnerPartId=-1|Location.X=1607|Location.X_Frac=50000|Location.Y=432|Color=8388608|FontID=2|IsHidden=T|Text=9/4/2013|Name=MODIFY DATE
|RECORD=41|OwnerIndex=607|IndexInSheet=2|OwnerPartId=-1|Location.X=1607|Location.X_Frac=50000|Location.Y=432|Color=8388608|FontID=2|IsHidden=T|Text=LUMEX|Name=MFG NAME
|RECORD=41|OwnerIndex=607|IndexInSheet=3|OwnerPartId=-1|Location.X=1607|Location.X_Frac=50000|Location.Y=432|Color=8388608|FontID=2|IsHidden=T|Text=LED|Name=CATEGORY
|RECORD=41|OwnerIndex=607|IndexInSheet=4|OwnerPartId=-1|Location.X=1607|Location.X_Frac=50000|Location.Y=432|Color=8388608|FontID=2|IsHidden=T|Name=Date
|RECORD=41|OwnerIndex=607|IndexInSheet=5|OwnerPartId=-1|Location.X=1607|Location.X_Frac=50000|Location.Y=432|Color=8388608|FontID=2|IsHidden=T|Text=85C|Name=MAXTEMP
|RECORD=41|OwnerIndex=607|IndexInSheet=6|OwnerPartId=-1|Location.X=1607|Location.X_Frac=50000|Location.Y=432|Color=8388608|FontID=2|IsHidden=T|Text=-25C|Name=MINTEMP
|RECORD=41|OwnerIndex=607|IndexInSheet=7|OwnerPartId=-1|Location.X=1607|Location.X_Frac=50000|Location.Y=432|Color=8388608|FontID=2|IsHidden=T|Text=SML-LX0603|Name=OTHER
|RECORD=41|OwnerIndex=607|IndexInSheet=8|OwnerPartId=-1|Location.X=1607|Location.X_Frac=50000|Location.Y=432|Color=8388608|FontID=2|IsHidden=T|Text=635NM|Name=P1
|RECORD=41|OwnerIndex=607|IndexInSheet=9|OwnerPartId=-1|Location.X=1607|Location.X_Frac=50000|Location.Y=432|Color=8388608|FontID=2|IsHidden=T|Text=2V|Name=P2
|RECORD=41|OwnerIndex=607|IndexInSheet=10|OwnerPartId=-1|Location.X=1607|Location.X_Frac=50000|Location.Y=432|Color=8388608|FontID=2|IsHidden=T|Text=20MA|Name=P3
|RECORD=41|OwnerIndex=607|IndexInSheet=11|OwnerPartId=-1|Location.X=1607|Location.X_Frac=50000|Location.Y=432|Color=8388608|FontID=2|IsHidden=T|Name=SUB
|RECORD=41|OwnerIndex=607|IndexInSheet=12|OwnerPartId=-1|Location.X=1607|Location.X_Frac=50000|Location.Y=432|Color=8388608|FontID=2|IsHidden=T|Text=0603|Name=SIZE
|RECORD=41|OwnerIndex=607|IndexInSheet=13|OwnerPartId=-1|Location.X=1607|Location.X_Frac=50000|Location.Y=432|Color=8388608|FontID=1|IsHidden=T|Text=*|Name=SHEETPART
|RECORD=41|OwnerIndex=607|IndexInSheet=14|OwnerPartId=-1|Location.X=1607|Location.X_Frac=50000|Location.Y=432|Color=8388608|FontID=1|IsHidden=T|Text=LED, RED, SML-LX0603, 635NM, 2V, 20MA, 0603|Name=DESC
|RECORD=41|OwnerIndex=607|IndexInSheet=15|OwnerPartId=-1|Location.X=1607|Location.X_Frac=50000|Location.Y=432|Color=8388608|FontID=1|IsHidden=T|Text=Digi-Key|Name=Supplier 1|ReadOnlyState=3
|RECORD=41|OwnerIndex=607|IndexInSheet=16|OwnerPartId=-1|Location.X=1607|Location.X_Frac=50000|Location.Y=432|Color=8388608|FontID=1|IsHidden=T|Text=67-1548-1-ND|Name=Supplier Part Number 1|ReadOnlyState=3
|RECORD=41|OwnerIndex=607|IndexInSheet=17|OwnerPartId=-1|Location.X=1640|Location.Y=386|Location.Y_Frac=50000|Color=8388608|FontID=2|Text=RED|Name=VALUE
|RECORD=2|OwnerIndex=607|OwnerPartId=1|FormalType=1|Electrical=4|PinConglomerate=33|PinLength=20|Location.X=1620|Location.Y=410|Name=A|Designator=2|PinPropagationDelay=0.000000E+000
|RECORD=2|OwnerIndex=607|OwnerPartId=1|FormalType=1|Electrical=4|PinConglomerate=35|PinLength=20|Location.X=1620|Location.Y=390|Name=K|Designator=1|PinPropagationDelay=0.000000E+000
|RECORD=12|OwnerIndex=607|IsNotAccesible=T|IndexInSheet=20|OwnerPartId=1|Location.X=1620|Location.Y=400|Radius=12|Radius_Frac=50000|LineWidth=1|EndAngle=360.000|Color=16711680
|RECORD=13|OwnerIndex=607|IsNotAccesible=T|IndexInSheet=21|OwnerPartId=1|Location.X=1628|Location.Y=394|Corner.X=1613|Corner.Y=394|LineWidth=1|Color=16711680
|RECORD=13|OwnerIndex=607|IsNotAccesible=T|IndexInSheet=22|OwnerPartId=1|Location.X=1635|Location.Y=381|Corner.X=1628|Corner.X_Frac=70000|Corner.Y=387|Corner.Y_Frac=20000|LineWidth=1|Color=16711680
|RECORD=13|OwnerIndex=607|IsNotAccesible=T|IndexInSheet=23|OwnerPartId=1|Location.X=1639|Location.Y=385|Corner.X=1632|Corner.X_Frac=80000|Corner.Y=391|Corner.Y_Frac=30000|LineWidth=1|Color=16711680
|RECORD=13|OwnerIndex=607|IsNotAccesible=T|IndexInSheet=24|OwnerPartId=1|Location.X=1620|Location.Y=390|Corner.X=1620|Corner.Y=393|Corner.Y_Frac=80000|LineWidth=1|Color=16711680
|RECORD=13|OwnerIndex=607|IsNotAccesible=T|IndexInSheet=25|OwnerPartId=1|Location.X=1620|Location.Y=406|Corner.X=1620|Corner.Y=409|Corner.Y_Frac=70000|LineWidth=1|Color=16711680
|RECORD=7|OwnerIndex=607|IsNotAccesible=T|IndexInSheet=26|OwnerPartId=1|LineWidth=1|Color=16711680|AreaColor=16711680|IsSolid=T|LocationCount=3|X1=1634|Y1=384|X2=1632|Y2=382|X3=1635|Y3=381
|RECORD=7|OwnerIndex=607|IsNotAccesible=T|IndexInSheet=27|OwnerPartId=1|LineWidth=1|Color=16711680|AreaColor=16711680|IsSolid=T|LocationCount=3|X1=1638|Y1=388|X2=1636|Y2=386|X3=1639|Y3=385
|RECORD=7|OwnerIndex=607|IsNotAccesible=T|IndexInSheet=28|OwnerPartId=1|LineWidth=1|Color=16711680|AreaColor=16777215|IsSolid=T|LocationCount=3|X1=1620|Y1=394|X2=1628|Y2=406|X3=1612|Y3=406
|RECORD=41|OwnerIndex=607|IndexInSheet=29|OwnerPartId=-1|Location.X=1607|Location.X_Frac=50000|Location.Y=432|Color=8388608|FontID=1|IsHidden=T|Text=<VALENTIUM>|Name=VALENTIUM PART NUM
|RECORD=34|OwnerIndex=607|IndexInSheet=-1|OwnerPartId=-1|Location.X=1640|Location.Y=398|Location.Y_Frac=50000|Color=8388608|FontID=3|Text=D4|Name=Designator|ReadOnlyState=1
|RECORD=41|OwnerIndex=607|IndexInSheet=-1|OwnerPartId=-1|Location.X=1607|Location.X_Frac=50000|Location.Y=432|Color=8388608|FontID=2|IsHidden=T|Text==VALUE|Name=Comment|ReadOnlyState=1
|RECORD=44|OwnerIndex=607
|RECORD=45|OwnerIndex=642|IndexInSheet=-1|Description=Molded Diode, 0603, 2-Leads, Body 1.60x0.80mm, IPC Medium Density|UseComponentLibrary=T|ModelName=DIOM1608X06N|ModelType=PCBLIB|DatafileCount=1|ModelDatafileEntity0=DIOM1608X06N|ModelDatafileKind0=PCBLib|IsCurrent=T|DatalinksLocked=T|DatabaseDatalinksLocked=T|IntegratedModel=T|DatabaseModel=T
|RECORD=46|OwnerIndex=643
|RECORD=48|OwnerIndex=643
|RECORD=1|LibReference=RES_0603_200|ComponentDescription=RES, 200 OHM, 1%, 1/10W, TF, 0603|PartCount=2|DisplayModeCount=1|IndexInSheet=62|OwnerPartId=-1|Location.X=1620|Location.Y=300|Orientation=1|CurrentPartId=1|LibraryPath=*|SourceLibraryName=Resistors.IntLib|TargetFileName=*|AreaColor=11599871|Color=128|PartIDLocked=F|DesignItemId=RES_0603_200|AllPinCount=2
|RECORD=41|OwnerIndex=646|OwnerPartId=-1|Location.X=1616|Location.Y=352|Color=8388608|FontID=2|IsHidden=T|Text=7/25/2013|Name=ModifyDate
|RECORD=41|OwnerIndex=646|IndexInSheet=1|OwnerPartId=-1|Location.X=1616|Location.Y=352|Color=8388608|FontID=2|IsHidden=T|Text=ERJ-3EKF2000V|Name=MFG PART NUM
|RECORD=41|OwnerIndex=646|IndexInSheet=2|OwnerPartId=-1|Location.X=1616|Location.Y=352|Color=8388608|FontID=2|IsHidden=T|Text=PANASONIC|Name=MFG NAME
|RECORD=41|OwnerIndex=646|IndexInSheet=3|OwnerPartId=-1|Location.X=1616|Location.Y=352|Color=8388608|FontID=2|IsHidden=T|Text=RES|Name=CATEGORY
|RECORD=41|OwnerIndex=646|IndexInSheet=4|OwnerPartId=-1|Location.X=1616|Location.Y=352|Color=8388608|FontID=2|IsHidden=T|Text=7/26/2013|Name=Date
|RECORD=41|OwnerIndex=646|IndexInSheet=5|OwnerPartId=-1|Location.X=1616|Location.Y=352|Color=8388608|FontID=2|IsHidden=T|Text=1%|Name=P1
|RECORD=41|OwnerIndex=646|IndexInSheet=6|OwnerPartId=-1|Location.X=1616|Location.Y=352|Color=8388608|FontID=2|IsHidden=T|Text=TF|Name=P3
|RECORD=41|OwnerIndex=646|IndexInSheet=7|OwnerPartId=-1|Location.X=1616|Location.Y=352|Color=8388608|FontID=2|IsHidden=T|Text=1/10W|Name=P2
|RECORD=41|OwnerIndex=646|IndexInSheet=8|OwnerPartId=-1|Location.X=1616|Location.Y=352|Color=8388608|FontID=2|IsHidden=T|Text=125C|Name=MAXTEMP
|RECORD=41|OwnerIndex=646|IndexInSheet=9|OwnerPartId=-1|Location.X=1616|Location.Y=352|Color=8388608|FontID=2|IsHidden=T|Text=-55C|Name=MINTEMP
|RECORD=41|OwnerIndex=646|IndexInSheet=10|OwnerPartId=-1|Location.X=1616|Location.Y=352|Color=8388608|FontID=2|IsHidden=T|Text=100PPM|Name=OTHER
|RECORD=41|OwnerIndex=646|IndexInSheet=11|OwnerPartId=-1|Location.X=1616|Location.Y=352|Color=8388608|FontID=2|IsHidden=T|Text=0603|Name=SIZE
|RECORD=41|OwnerIndex=646|IndexInSheet=12|OwnerPartId=-1|Location.X=1616|Location.Y=352|Color=8388608|FontID=2|IsHidden=T|Text=GENERIC|Name=SUB
|RECORD=41|OwnerIndex=646|IndexInSheet=13|OwnerPartId=-1|Location.X=1616|Location.Y=352|Color=8388608|FontID=1|IsHidden=T|Text=*|Name=SHEETPART
|RECORD=41|OwnerIndex=646|IndexInSheet=14|OwnerPartId=-1|Location.X=1616|Location.Y=352|Color=8388608|FontID=1|IsHidden=T|Text=RES, 200 OHM, 1%, 1/10W, TF, 0603|Name=DESC
|RECORD=41|OwnerIndex=646|IndexInSheet=15|OwnerPartId=-1|Location.X=1616|Location.Y=352|Color=8388608|FontID=1|IsHidden=T|Text=Digi-Key|Name=Supplier 1|ReadOnlyState=3
|RECORD=41|OwnerIndex=646|IndexInSheet=16|OwnerPartId=-1|Location.X=1616|Location.Y=352|Color=8388608|FontID=1|IsHidden=T|Text=P200HCT-ND|Name=Supplier Part Number 1|ReadOnlyState=3
|RECORD=41|OwnerIndex=646|IndexInSheet=17|OwnerPartId=-1|Location.X=1616|Location.Y=352|Color=8388608|FontID=1|IsHidden=T|Text=<VELENTIUM>|Name=VELENTIUM PART NUM
|RECORD=41|OwnerIndex=646|IndexInSheet=18|OwnerPartId=-1|Location.X=1624|Location.Y=315|Color=8388608|FontID=2|Text=200 OHM|Name=VALUE
|RECORD=2|OwnerIndex=646|OwnerPartId=1|FormalType=1|Electrical=4|PinConglomerate=35|PinLength=10|Location.X=1620|Location.Y=310|Name=1|Designator=1|PinPropagationDelay=0.000000E+000
|RECORD=2|OwnerIndex=646|OwnerPartId=1|FormalType=1|Electrical=4|PinConglomerate=33|PinLength=10|Location.X=1620|Location.Y=340|Name=2|Designator=2|PinPropagationDelay=0.000000E+000
|RECORD=6|OwnerIndex=646|IsNotAccesible=T|IndexInSheet=21|OwnerPartId=1|LineWidth=1|Color=16711680|LocationCount=7|X1=1620|Y1=340|X2=1617|Y2=337|X3=1623|Y3=331|X4=1617|Y4=325|X5=1623|Y5=319|X6=1617|Y6=313|X7=1620|Y7=310
|RECORD=34|OwnerIndex=646|IndexInSheet=-1|OwnerPartId=-1|Location.X=1624|Location.Y=327|Color=8388608|FontID=3|Text=R1|Name=Designator|ReadOnlyState=1
|RECORD=41|OwnerIndex=646|IndexInSheet=-1|OwnerPartId=-1|Location.X=1616|Location.Y=352|Color=8388608|FontID=2|IsHidden=T|Text==MFG PART NUM|Name=Comment
|RECORD=44|OwnerIndex=646
|RECORD=45|OwnerIndex=673|IndexInSheet=-1|Description=Chip Resistor, 0603, 2-Leads, Body 1.57x0.85mm, IPC Medium Density|UseComponentLibrary=T|ModelName=RESC1608X50N|ModelType=PCBLIB|DatafileCount=1|ModelDatafileEntity0=RESC1608X50N|ModelDatafileKind0=PCBLib|IsCurrent=T|DatalinksLocked=T|DatabaseDatalinksLocked=T|IntegratedModel=T|DatabaseModel=T
|RECORD=46|OwnerIndex=674
|RECORD=48|OwnerIndex=674
|RECORD=1|LibReference=RES_0603_47K|ComponentDescription=RES, 47K, 1%, 1/10W, TF, 0603|PartCount=2|DisplayModeCount=1|IndexInSheet=63|OwnerPartId=-1|Location.X=110|Location.Y=490|Orientation=1|CurrentPartId=1|LibraryPath=*|SourceLibraryName=Resistors.IntLib|TargetFileName=*|AreaColor=11599871|Color=128|PartIDLocked=F|DesignItemId=RES_0603_47K|AllPinCount=2
|RECORD=41|OwnerIndex=677|OwnerPartId=-1|Location.X=106|Location.Y=542|Color=8388608|FontID=2|IsHidden=T|Text=1/22/2014|Name=ModifyDate
|RECORD=41|OwnerIndex=677|IndexInSheet=1|OwnerPartId=-1|Location.X=106|Location.Y=542|Color=8388608|FontID=2|IsHidden=T|Text=ERJ-3EKF4702V|Name=MFG PART NUM
|RECORD=41|OwnerIndex=677|IndexInSheet=2|OwnerPartId=-1|Location.X=106|Location.Y=542|Color=8388608|FontID=2|IsHidden=T|Text=PANASONIC|Name=MFG NAME
|RECORD=41|OwnerIndex=677|IndexInSheet=3|OwnerPartId=-1|Location.X=106|Location.Y=542|Color=8388608|FontID=2|IsHidden=T|Text=RES|Name=CATEGORY
|RECORD=41|OwnerIndex=677|IndexInSheet=4|OwnerPartId=-1|Location.X=106|Location.Y=542|Color=8388608|FontID=2|IsHidden=T|Text=1/22/2014|Name=Date
|RECORD=41|OwnerIndex=677|IndexInSheet=5|OwnerPartId=-1|Location.X=106|Location.Y=542|Color=8388608|FontID=2|IsHidden=T|Text=1%|Name=P1
|RECORD=41|OwnerIndex=677|IndexInSheet=6|OwnerPartId=-1|Location.X=106|Location.Y=542|Color=8388608|FontID=2|IsHidden=T|Text=TF|Name=P3
|RECORD=41|OwnerIndex=677|IndexInSheet=7|OwnerPartId=-1|Location.X=106|Location.Y=542|Color=8388608|FontID=2|IsHidden=T|Text=1/10W|Name=P2
|RECORD=41|OwnerIndex=677|IndexInSheet=8|OwnerPartId=-1|Location.X=106|Location.Y=542|Color=8388608|FontID=2|IsHidden=T|Text=125C|Name=MAXTEMP
|RECORD=41|OwnerIndex=677|IndexInSheet=9|OwnerPartId=-1|Location.X=106|Location.Y=542|Color=8388608|FontID=2|IsHidden=T|Text=-55C|Name=MINTEMP
|RECORD=41|OwnerIndex=677|IndexInSheet=10|OwnerPartId=-1|Location.X=106|Location.Y=542|Color=8388608|FontID=2|IsHidden=T|Text=100PPM|Name=OTHER
|RECORD=41|OwnerIndex=677|IndexInSheet=11|OwnerPartId=-1|Location.X=106|Location.Y=542|Color=8388608|FontID=2|IsHidden=T|Text=0603|Name=SIZE
|RECORD=41|OwnerIndex=677|IndexInSheet=12|OwnerPartId=-1|Location.X=106|Location.Y=542|Color=8388608|FontID=2|IsHidden=T|Text=GENERIC|Name=SUB
|RECORD=41|OwnerIndex=677|IndexInSheet=13|OwnerPartId=-1|Location.X=106|Location.Y=542|Color=8388608|FontID=1|IsHidden=T|Text=*|Name=SHEETPART
|RECORD=41|OwnerIndex=677|IndexInSheet=14|OwnerPartId=-1|Location.X=106|Location.Y=542|Color=8388608|FontID=1|IsHidden=T|Text=RES, 47K, 1%, 1/10W, TF, 0603|Name=DESC
|RECORD=41|OwnerIndex=677|IndexInSheet=15|OwnerPartId=-1|Location.X=106|Location.Y=542|Color=8388608|FontID=1|IsHidden=T|Text=Digi-Key|Name=Supplier 1|ReadOnlyState=3
|RECORD=41|OwnerIndex=677|IndexInSheet=16|OwnerPartId=-1|Location.X=106|Location.Y=542|Color=8388608|FontID=1|IsHidden=T|Text=P47.0KHCT-ND|Name=Supplier Part Number 1|ReadOnlyState=3
|RECORD=41|OwnerIndex=677|IndexInSheet=17|OwnerPartId=-1|Location.X=114|Location.Y=505|Color=8388608|FontID=2|Text=47K|Name=VALUE
|RECORD=2|OwnerIndex=677|OwnerPartId=1|FormalType=1|Electrical=4|PinConglomerate=35|PinLength=10|Location.X=110|Location.Y=500|Name=1|Designator=1|PinPropagationDelay=0.000000E+000
|RECORD=2|OwnerIndex=677|OwnerPartId=1|FormalType=1|Electrical=4|PinConglomerate=33|PinLength=10|Location.X=110|Location.Y=530|Name=2|Designator=2|PinPropagationDelay=0.000000E+000
|RECORD=6|OwnerIndex=677|IsNotAccesible=T|IndexInSheet=20|OwnerPartId=1|LineWidth=1|Color=16711680|LocationCount=7|X1=110|Y1=530|X2=107|Y2=527|X3=113|Y3=521|X4=107|Y4=515|X5=113|Y5=509|X6=107|Y6=503|X7=110|Y7=500
|RECORD=41|OwnerIndex=677|IndexInSheet=21|OwnerPartId=-1|Location.X=106|Location.Y=542|Color=8388608|FontID=1|IsHidden=T|Text=<VELENTIUM>|Name=VELENTIUM PART NUM
|RECORD=34|OwnerIndex=677|IndexInSheet=-1|OwnerPartId=-1|Location.X=114|Location.Y=517|Color=8388608|FontID=3|Text=R2|Name=Designator|ReadOnlyState=1
|RECORD=41|OwnerIndex=677|IndexInSheet=-1|OwnerPartId=-1|Location.X=106|Location.Y=542|Color=8388608|FontID=2|IsHidden=T|Text==MFG PART NUM|Name=Comment
|RECORD=44|OwnerIndex=677
|RECORD=45|OwnerIndex=704|IndexInSheet=-1|Description=Chip Resistor, 0603, 2-Leads, Body 1.57x0.85mm, IPC Medium Density|UseComponentLibrary=T|ModelName=RESC1608X50N|ModelType=PCBLIB|DatafileCount=1|ModelDatafileEntity0=RESC1608X50N|ModelDatafileKind0=PCBLib|IsCurrent=T|DatalinksLocked=T|DatabaseDatalinksLocked=T|IntegratedModel=T|DatabaseModel=T
|RECORD=46|OwnerIndex=705
|RECORD=48|OwnerIndex=705
|RECORD=1|LibReference=RES_0603_2.2K|ComponentDescription=RES, 2.2K, 1%, 1/10W, TF, 0603|PartCount=2|DisplayModeCount=1|IndexInSheet=64|OwnerPartId=-1|Location.X=210|Location.Y=320|CurrentPartId=1|LibraryPath=*|SourceLibraryName=Resistors.IntLib|TargetFileName=*|AreaColor=11599871|Color=128|PartIDLocked=F|DesignItemId=RES_0603_2.2K|AllPinCount=2
|RECORD=41|OwnerIndex=708|OwnerPartId=-1|Location.X=210|Location.Y=320|Color=8388608|FontID=2|IsHidden=T|Text=8/15/2013|Name=ModifyDate
|RECORD=41|OwnerIndex=708|IndexInSheet=1|OwnerPartId=-1|Location.X=210|Location.Y=320|Color=8388608|FontID=2|IsHidden=T|Text=ERJ-3EKF2201V|Name=MFG PART NUM
|RECORD=41|OwnerIndex=708|IndexInSheet=2|OwnerPartId=-1|Location.X=210|Location.Y=320|Color=8388608|FontID=2|IsHidden=T|Text=PANASONIC|Name=MFG NAME
|RECORD=41|OwnerIndex=708|IndexInSheet=3|OwnerPartId=-1|Location.X=210|Location.Y=320|Color=8388608|FontID=2|IsHidden=T|Text=RES|Name=CATEGORY
|RECORD=41|OwnerIndex=708|IndexInSheet=4|OwnerPartId=-1|Location.X=208|Location.Y=330|Color=8388608|FontID=2|IsHidden=T|Text=8/15/2013|Name=Date
|RECORD=41|OwnerIndex=708|IndexInSheet=5|OwnerPartId=-1|Location.X=200|Location.X_Frac=55769|Location.Y=330|Color=8388608|FontID=2|IsHidden=T|Text=1%|Name=P1
|RECORD=41|OwnerIndex=708|IndexInSheet=6|OwnerPartId=-1|Location.X=200|Location.X_Frac=55769|Location.Y=330|Color=8388608|FontID=2|IsHidden=T|Text=TF|Name=P3
|RECORD=41|OwnerIndex=708|IndexInSheet=7|OwnerPartId=-1|Location.X=200|Location.X_Frac=55769|Location.Y=330|Color=8388608|FontID=2|IsHidden=T|Text=1/10W|Name=P2
|RECORD=41|OwnerIndex=708|IndexInSheet=8|OwnerPartId=-1|Location.X=200|Location.X_Frac=55769|Location.Y=330|Color=8388608|FontID=2|IsHidden=T|Text=125C|Name=MAXTEMP
|RECORD=41|OwnerIndex=708|IndexInSheet=9|OwnerPartId=-1|Location.X=200|Location.X_Frac=55769|Location.Y=330|Color=8388608|FontID=2|IsHidden=T|Text=-55C|Name=MINTEMP
|RECORD=41|OwnerIndex=708|IndexInSheet=10|OwnerPartId=-1|Location.X=200|Location.X_Frac=55769|Location.Y=330|Color=8388608|FontID=2|IsHidden=T|Text=100PPM|Name=OTHER
|RECORD=41|OwnerIndex=708|IndexInSheet=11|OwnerPartId=-1|Location.X=200|Location.X_Frac=55769|Location.Y=330|Color=8388608|FontID=2|IsHidden=T|Text=0603|Name=SIZE
|RECORD=41|OwnerIndex=708|IndexInSheet=12|OwnerPartId=-1|Location.X=200|Location.X_Frac=55769|Location.Y=330|Color=8388608|FontID=2|IsHidden=T|Text=GENERIC|Name=SUB
|RECORD=41|OwnerIndex=708|IndexInSheet=13|OwnerPartId=-1|Location.X=195|Location.X_Frac=98077|Location.Y=334|Color=8388608|FontID=2|IsHidden=T|Text=Digi-Key|Name=Supplier 1|ReadOnlyState=3
|RECORD=41|OwnerIndex=708|IndexInSheet=14|OwnerPartId=-1|Location.X=195|Location.X_Frac=98077|Location.Y=334|Color=8388608|FontID=2|IsHidden=T|Text=P2.20KHCT-ND|Name=Supplier Part Number 1|ReadOnlyState=3
|RECORD=41|OwnerIndex=708|IndexInSheet=15|OwnerPartId=-1|Location.X=195|Location.X_Frac=98077|Location.Y=306|Color=8388608|FontID=1|IsHidden=T|Text=*|Name=SHEETPART
|RECORD=41|OwnerIndex=708|IndexInSheet=16|OwnerPartId=-1|Location.X=195|Location.X_Frac=98077|Location.Y=334|Color=8388608|FontID=1|IsHidden=T|Text=RES, 2.2K, 1%, 1/10W, TF, 0603|Name=DESC
|RECORD=41|OwnerIndex=708|IndexInSheet=17|OwnerPartId=-1|Location.X=219|Location.Y=304|Color=8388608|FontID=2|Text=2.2K|Name=VALUE
|RECORD=2|OwnerIndex=708|OwnerPartId=1|FormalType=1|Electrical=4|PinConglomerate=34|PinLength=10|Location.X=220|Location.Y=320|Name=1|Designator=1|PinPropagationDelay=0.000000E+000
|RECORD=2|OwnerIndex=708|OwnerPartId=1|FormalType=1|Electrical=4|PinConglomerate=32|PinLength=10|Location.X=250|Location.Y=320|Name=2|Designator=2|PinPropagationDelay=0.000000E+000
|RECORD=6|OwnerIndex=708|IsNotAccesible=T|IndexInSheet=20|OwnerPartId=1|LineWidth=1|Color=16711680|LocationCount=7|X1=250|Y1=320|X2=247|Y2=323|X3=241|Y3=317|X4=235|Y4=323|X5=229|Y5=317|X6=223|Y6=323|X7=220|Y7=320
|RECORD=41|OwnerIndex=708|IndexInSheet=21|OwnerPartId=-1|Location.X=196|Location.X_Frac=61102|Location.Y=334|Color=8388608|FontID=1|IsHidden=T|Text=<VELENTIUM>|Name=VELENTIUM PART NUM
|RECORD=34|OwnerIndex=708|IndexInSheet=-1|OwnerPartId=-1|Location.X=219|Location.Y=324|Color=8388608|FontID=3|Text=R8|Name=Designator|ReadOnlyState=1
|RECORD=41|OwnerIndex=708|IndexInSheet=-1|OwnerPartId=-1|Location.X=230|Location.Y=310|Color=8388608|FontID=2|IsHidden=T|Text==MFG PART NUM|Name=Comment
|RECORD=44|OwnerIndex=708
|RECORD=45|OwnerIndex=735|IndexInSheet=-1|Description=Chip Resistor, 0603, 2-Leads, Body 1.57x0.85mm, IPC Medium Density|UseComponentLibrary=T|ModelName=RESC1608X50N|ModelType=PCBLIB|DatafileCount=1|ModelDatafileEntity0=RESC1608X50N|ModelDatafileKind0=PCBLib|IsCurrent=T|DatalinksLocked=T|DatabaseDatalinksLocked=T|IntegratedModel=T|DatabaseModel=T
|RECORD=46|OwnerIndex=736
|RECORD=48|OwnerIndex=736
|RECORD=1|LibReference=RES_0603_10K|ComponentDescription=RES, 10K, 1%, 1/10W, TF, 0603|PartCount=2|DisplayModeCount=1|IndexInSheet=65|OwnerPartId=-1|Location.X=380|Location.Y=350|Orientation=1|CurrentPartId=1|LibraryPath=*|SourceLibraryName=Resistors.IntLib|TargetFileName=*|AreaColor=11599871|Color=128|PartIDLocked=F|DesignItemId=RES_0603_10K|AllPinCount=2
|RECORD=41|OwnerIndex=739|OwnerPartId=-1|Location.X=376|Location.Y=402|Color=8388608|FontID=2|IsHidden=T|Text=7/25/2013|Name=ModifyDate
|RECORD=41|OwnerIndex=739|IndexInSheet=1|OwnerPartId=-1|Location.X=376|Location.Y=402|Color=8388608|FontID=2|IsHidden=T|Text=ERJ-3EKF1002V|Name=MFG PART NUM
|RECORD=41|OwnerIndex=739|IndexInSheet=2|OwnerPartId=-1|Location.X=376|Location.Y=402|Color=8388608|FontID=2|IsHidden=T|Text=PANASONIC|Name=MFG NAME
|RECORD=41|OwnerIndex=739|IndexInSheet=3|OwnerPartId=-1|Location.X=376|Location.Y=402|Color=8388608|FontID=2|IsHidden=T|Text=RES|Name=CATEGORY
|RECORD=41|OwnerIndex=739|IndexInSheet=4|OwnerPartId=-1|Location.X=376|Location.Y=402|Color=8388608|FontID=2|IsHidden=T|Text=7/26/2013|Name=Date
|RECORD=41|OwnerIndex=739|IndexInSheet=5|OwnerPartId=-1|Location.X=376|Location.Y=402|Color=8388608|FontID=2|IsHidden=T|Text=1%|Name=P1
|RECORD=41|OwnerIndex=739|IndexInSheet=6|OwnerPartId=-1|Location.X=376|Location.Y=402|Color=8388608|FontID=2|IsHidden=T|Text=TF|Name=P3
|RECORD=41|OwnerIndex=739|IndexInSheet=7|OwnerPartId=-1|Location.X=376|Location.Y=402|Color=8388608|FontID=2|IsHidden=T|Text=1/10W|Name=P2
|RECORD=41|OwnerIndex=739|IndexInSheet=8|OwnerPartId=-1|Location.X=376|Location.Y=402|Color=8388608|FontID=2|IsHidden=T|Text=125C|Name=MAXTEMP
|RECORD=41|OwnerIndex=739|IndexInSheet=9|OwnerPartId=-1|Location.X=376|Location.Y=402|Color=8388608|FontID=2|IsHidden=T|Text=-55C|Name=MINTEMP
|RECORD=41|OwnerIndex=739|IndexInSheet=10|OwnerPartId=-1|Location.X=376|Location.Y=402|Color=8388608|FontID=2|IsHidden=T|Text=100PPM|Name=OTHER
|RECORD=41|OwnerIndex=739|IndexInSheet=11|OwnerPartId=-1|Location.X=376|Location.Y=402|Color=8388608|FontID=2|IsHidden=T|Text=0603|Name=SIZE
|RECORD=41|OwnerIndex=739|IndexInSheet=12|OwnerPartId=-1|Location.X=376|Location.Y=402|Color=8388608|FontID=2|IsHidden=T|Text=GENERIC|Name=SUB
|RECORD=41|OwnerIndex=739|IndexInSheet=13|OwnerPartId=-1|Location.X=376|Location.Y=402|Color=8388608|FontID=2|IsHidden=T|Text=Digi-Key|Name=Supplier 1|ReadOnlyState=3
|RECORD=41|OwnerIndex=739|IndexInSheet=14|OwnerPartId=-1|Location.X=376|Location.Y=402|Color=8388608|FontID=2|IsHidden=T|Text=P10.0KHCT-ND|Name=Supplier Part Number 1|ReadOnlyState=3
|RECORD=41|OwnerIndex=739|IndexInSheet=15|OwnerPartId=-1|Location.X=376|Location.Y=402|Color=8388608|FontID=1|IsHidden=T|Text=*|Name=SHEETPART
|RECORD=41|OwnerIndex=739|IndexInSheet=16|OwnerPartId=-1|Location.X=376|Location.Y=402|Color=8388608|FontID=1|IsHidden=T|Text=RES, 10K, 1%, 1/10W, TF, 0603|Name=DESC
|RECORD=41|OwnerIndex=739|IndexInSheet=17|OwnerPartId=-1|Location.X=384|Location.Y=365|Color=8388608|FontID=2|Text=10K|Name=VALUE
|RECORD=2|OwnerIndex=739|OwnerPartId=1|FormalType=1|Electrical=4|PinConglomerate=35|PinLength=10|Location.X=380|Location.Y=360|Name=1|Designator=1|PinPropagationDelay=0.000000E+000
|RECORD=2|OwnerIndex=739|OwnerPartId=1|FormalType=1|Electrical=4|PinConglomerate=33|PinLength=10|Location.X=380|Location.Y=390|Name=2|Designator=2|PinPropagationDelay=0.000000E+000
|RECORD=6|OwnerIndex=739|IsNotAccesible=T|IndexInSheet=20|OwnerPartId=1|LineWidth=1|Color=16711680|LocationCount=7|X1=380|Y1=390|X2=377|Y2=387|X3=383|Y3=381|X4=377|Y4=375|X5=383|Y5=369|X6=377|Y6=363|X7=380|Y7=360
|RECORD=41|OwnerIndex=739|IndexInSheet=21|OwnerPartId=-1|Location.X=376|Location.Y=402|Color=8388608|FontID=1|IsHidden=T|Text=<VELENTIUM>|Name=VELENTIUM PART NUM
|RECORD=34|OwnerIndex=739|IndexInSheet=-1|OwnerPartId=-1|Location.X=384|Location.Y=377|Color=8388608|FontID=3|Text=R6|Name=Designator|ReadOnlyState=1
|RECORD=41|OwnerIndex=739|IndexInSheet=-1|OwnerPartId=-1|Location.X=376|Location.Y=402|Color=8388608|FontID=2|IsHidden=T|Text==MFG PART NUM|Name=Comment
|RECORD=44|OwnerIndex=739
|RECORD=45|OwnerIndex=766|IndexInSheet=-1|Description=Chip Resistor, 0603, 2-Leads, Body 1.57x0.85mm, IPC Medium Density|UseComponentLibrary=T|ModelName=RESC1608X50N|ModelType=PCBLIB|DatafileCount=1|ModelDatafileEntity0=RESC1608X50N|ModelDatafileKind0=PCBLib|IsCurrent=T|DatalinksLocked=T|DatabaseDatalinksLocked=T|IntegratedModel=T|DatabaseModel=T
|RECORD=46|OwnerIndex=767
|RECORD=48|OwnerIndex=767
|RECORD=1|LibReference=RES_0603_47K|ComponentDescription=RES, 47K, 1%, 1/10W, TF, 0603|PartCount=2|DisplayModeCount=1|IndexInSheet=66|OwnerPartId=-1|Location.X=440|Location.Y=430|Orientation=2|CurrentPartId=1|LibraryPath=*|SourceLibraryName=Resistors.IntLib|TargetFileName=*|AreaColor=11599871|Color=128|PartIDLocked=F|DesignItemId=RES_0603_47K|AllPinCount=2
|RECORD=41|OwnerIndex=770|OwnerPartId=-1|Location.X=388|Location.Y=434|Color=8388608|FontID=2|IsHidden=T|Text=1/22/2014|Name=ModifyDate
|RECORD=41|OwnerIndex=770|IndexInSheet=1|OwnerPartId=-1|Location.X=388|Location.Y=434|Color=8388608|FontID=2|IsHidden=T|Text=ERJ-3EKF4702V|Name=MFG PART NUM
|RECORD=41|OwnerIndex=770|IndexInSheet=2|OwnerPartId=-1|Location.X=388|Location.Y=434|Color=8388608|FontID=2|IsHidden=T|Text=PANASONIC|Name=MFG NAME
|RECORD=41|OwnerIndex=770|IndexInSheet=3|OwnerPartId=-1|Location.X=388|Location.Y=434|Color=8388608|FontID=2|IsHidden=T|Text=RES|Name=CATEGORY
|RECORD=41|OwnerIndex=770|IndexInSheet=4|OwnerPartId=-1|Location.X=388|Location.Y=434|Color=8388608|FontID=2|IsHidden=T|Text=1/22/2014|Name=Date
|RECORD=41|OwnerIndex=770|IndexInSheet=5|OwnerPartId=-1|Location.X=388|Location.Y=434|Color=8388608|FontID=2|IsHidden=T|Text=1%|Name=P1
|RECORD=41|OwnerIndex=770|IndexInSheet=6|OwnerPartId=-1|Location.X=388|Location.Y=434|Color=8388608|FontID=2|IsHidden=T|Text=TF|Name=P3
|RECORD=41|OwnerIndex=770|IndexInSheet=7|OwnerPartId=-1|Location.X=388|Location.Y=434|Color=8388608|FontID=2|IsHidden=T|Text=1/10W|Name=P2
|RECORD=41|OwnerIndex=770|IndexInSheet=8|OwnerPartId=-1|Location.X=388|Location.Y=434|Color=8388608|FontID=2|IsHidden=T|Text=125C|Name=MAXTEMP
|RECORD=41|OwnerIndex=770|IndexInSheet=9|OwnerPartId=-1|Location.X=388|Location.Y=434|Color=8388608|FontID=2|IsHidden=T|Text=-55C|Name=MINTEMP
|RECORD=41|OwnerIndex=770|IndexInSheet=10|OwnerPartId=-1|Location.X=388|Location.Y=434|Color=8388608|FontID=2|IsHidden=T|Text=100PPM|Name=OTHER
|RECORD=41|OwnerIndex=770|IndexInSheet=11|OwnerPartId=-1|Location.X=388|Location.Y=434|Color=8388608|FontID=2|IsHidden=T|Text=0603|Name=SIZE
|RECORD=41|OwnerIndex=770|IndexInSheet=12|OwnerPartId=-1|Location.X=388|Location.Y=434|Color=8388608|FontID=2|IsHidden=T|Text=GENERIC|Name=SUB
|RECORD=41|OwnerIndex=770|IndexInSheet=13|OwnerPartId=-1|Location.X=388|Location.Y=434|Color=8388608|FontID=1|IsHidden=T|Text=*|Name=SHEETPART
|RECORD=41|OwnerIndex=770|IndexInSheet=14|OwnerPartId=-1|Location.X=388|Location.Y=434|Color=8388608|FontID=1|IsHidden=T|Text=RES, 47K, 1%, 1/10W, TF, 0603|Name=DESC
|RECORD=41|OwnerIndex=770|IndexInSheet=15|OwnerPartId=-1|Location.X=388|Location.Y=434|Color=8388608|FontID=1|IsHidden=T|Text=Digi-Key|Name=Supplier 1|ReadOnlyState=3
|RECORD=41|OwnerIndex=770|IndexInSheet=16|OwnerPartId=-1|Location.X=388|Location.Y=434|Color=8388608|FontID=1|IsHidden=T|Text=P47.0KHCT-ND|Name=Supplier Part Number 1|ReadOnlyState=3
|RECORD=41|OwnerIndex=770|IndexInSheet=17|OwnerPartId=-1|Location.X=399|Location.Y=414|Color=8388608|FontID=2|Text=47K|Name=VALUE
|RECORD=2|OwnerIndex=770|OwnerPartId=1|FormalType=1|Electrical=4|PinConglomerate=32|PinLength=10|Location.X=430|Location.Y=430|Name=1|Designator=1|PinPropagationDelay=0.000000E+000
|RECORD=2|OwnerIndex=770|OwnerPartId=1|FormalType=1|Electrical=4|PinConglomerate=34|PinLength=10|Location.X=400|Location.Y=430|Name=2|Designator=2|PinPropagationDelay=0.000000E+000
|RECORD=6|OwnerIndex=770|IsNotAccesible=T|IndexInSheet=20|OwnerPartId=1|LineWidth=1|Color=16711680|LocationCount=7|X1=400|Y1=430|X2=403|Y2=427|X3=409|Y3=433|X4=415|Y4=427|X5=421|Y5=433|X6=427|Y6=427|X7=430|Y7=430
|RECORD=41|OwnerIndex=770|IndexInSheet=21|OwnerPartId=-1|Location.X=388|Location.Y=434|Color=8388608|FontID=1|IsHidden=T|Text=<VELENTIUM>|Name=VELENTIUM PART NUM
|RECORD=34|OwnerIndex=770|IndexInSheet=-1|OwnerPartId=-1|Location.X=399|Location.Y=434|Color=8388608|FontID=3|Text=R4|Name=Designator|ReadOnlyState=1
|RECORD=41|OwnerIndex=770|IndexInSheet=-1|OwnerPartId=-1|Location.X=388|Location.Y=434|Color=8388608|FontID=2|IsHidden=T|Text==MFG PART NUM|Name=Comment
|RECORD=44|OwnerIndex=770
|RECORD=45|OwnerIndex=797|IndexInSheet=-1|Description=Chip Resistor, 0603, 2-Leads, Body 1.57x0.85mm, IPC Medium Density|UseComponentLibrary=T|ModelName=RESC1608X50N|ModelType=PCBLIB|DatafileCount=1|ModelDatafileEntity0=RESC1608X50N|ModelDatafileKind0=PCBLib|IsCurrent=T|DatalinksLocked=T|DatabaseDatalinksLocked=T|IntegratedModel=T|DatabaseModel=T
|RECORD=46|OwnerIndex=798
|RECORD=48|OwnerIndex=798
|RECORD=1|LibReference=CAP_0603_0.01UF_50V|ComponentDescription=CAP, CER, 0.01UF, 50V, 10%, X7R, 0603|PartCount=2|DisplayModeCount=1|IndexInSheet=67|OwnerPartId=-1|Location.X=370|Location.Y=530|Orientation=1|CurrentPartId=1|LibraryPath=*|SourceLibraryName=Capacitors.IntLib|TargetFileName=*|AreaColor=11599871|Color=128|PartIDLocked=F|DesignItemId=CAP_0603_0.01UF_50V|AllPinCount=2
|RECORD=41|OwnerIndex=801|OwnerPartId=-1|Location.X=318|Location.Y=556|Color=8388608|FontID=2|IsHidden=T|Text=CAP, CER|Name=CATEGORY
|RECORD=41|OwnerIndex=801|IndexInSheet=1|OwnerPartId=-1|Location.X=318|Location.Y=556|Color=8388608|FontID=2|IsHidden=T|Text=KEMET|Name=MFG NAME
|RECORD=41|OwnerIndex=801|IndexInSheet=2|OwnerPartId=-1|Location.X=318|Location.Y=556|Color=8388608|FontID=2|IsHidden=T|Text=C0603C103K5RACTU|Name=MFG PART NUM
|RECORD=41|OwnerIndex=801|IndexInSheet=3|OwnerPartId=-1|Location.X=318|Location.Y=556|Color=8388608|FontID=2|IsHidden=T|Text=10/23/2013|Name=MODIFY DATE
|RECORD=41|OwnerIndex=801|IndexInSheet=4|OwnerPartId=-1|Location.X=318|Location.Y=556|Color=8388608|FontID=2|IsHidden=T|Text=7/24/2013|Name=Date
|RECORD=41|OwnerIndex=801|IndexInSheet=5|OwnerPartId=-1|Location.X=318|Location.Y=556|Color=8388608|FontID=2|IsHidden=T|Text=*|Name=SHEETPART
|RECORD=41|OwnerIndex=801|IndexInSheet=6|OwnerPartId=-1|Location.X=318|Location.Y=556|Color=8388608|FontID=2|IsHidden=T|Text=10%|Name=P1
|RECORD=41|OwnerIndex=801|IndexInSheet=7|OwnerPartId=-1|Location.X=318|Location.Y=556|Color=8388608|FontID=2|IsHidden=T|Text=125C|Name=MAXTEMP
|RECORD=41|OwnerIndex=801|IndexInSheet=8|OwnerPartId=-1|Location.X=318|Location.Y=556|Color=8388608|FontID=2|IsHidden=T|Text=-55C|Name=MINTEMP
|RECORD=41|OwnerIndex=801|IndexInSheet=9|OwnerPartId=-1|Location.X=318|Location.Y=556|Color=8388608|FontID=2|IsHidden=T|Name=OTHER
|RECORD=41|OwnerIndex=801|IndexInSheet=10|OwnerPartId=-1|Location.X=318|Location.Y=556|Color=8388608|FontID=2|IsHidden=T|Text=50V|Name=P2
|RECORD=41|OwnerIndex=801|IndexInSheet=11|OwnerPartId=-1|Location.X=318|Location.Y=556|Color=8388608|FontID=2|IsHidden=T|Text=X7R|Name=P3
|RECORD=41|OwnerIndex=801|IndexInSheet=12|OwnerPartId=-1|Location.X=318|Location.Y=556|Color=8388608|FontID=2|IsHidden=T|Text=0603|Name=Size
|RECORD=41|OwnerIndex=801|IndexInSheet=13|OwnerPartId=-1|Location.X=318|Location.Y=556|Color=8388608|FontID=2|IsHidden=T|Name=SUB
|RECORD=41|OwnerIndex=801|IndexInSheet=14|OwnerPartId=-1|Location.X=318|Location.Y=556|Color=8388608|FontID=2|IsHidden=T|Text=Digi-Key|Name=Supplier 1|ReadOnlyState=3
|RECORD=41|OwnerIndex=801|IndexInSheet=15|OwnerPartId=-1|Location.X=318|Location.Y=556|Color=8388608|FontID=2|IsHidden=T|Text=399-1091-1-ND|Name=Supplier Part Number 1|ReadOnlyState=3
|RECORD=41|OwnerIndex=801|IndexInSheet=16|OwnerPartId=-1|Location.X=318|Location.Y=556|Color=8388608|FontID=1|IsHidden=T|Text=CAP, CER, 0.01UF, 50V, 10%, X7R, 0603|Name=DESC
|RECORD=41|OwnerIndex=801|IndexInSheet=17|OwnerPartId=-1|Location.X=329|Location.Y=532|Color=8388608|FontID=2|Text=0.01uF|Name=VALUE
|RECORD=2|OwnerIndex=801|OwnerPartId=1|FormalType=1|Electrical=4|PinConglomerate=32|PinLength=10|Location.X=340|Location.Y=550|Name=2|Designator=2|SwapIdPin=2|SwapIDPart=1|PinPropagationDelay=0.000000E+000
|RECORD=2|OwnerIndex=801|OwnerPartId=1|FormalType=1|Electrical=4|PinConglomerate=34|PinLength=10|Location.X=330|Location.Y=550|Name=1|Designator=1|SwapIdPin=1|SwapIDPart=1|PinPropagationDelay=0.000000E+000
|RECORD=13|OwnerIndex=801|IsNotAccesible=T|IndexInSheet=20|OwnerPartId=1|Location.X=337|Location.X_Frac=50000|Location.Y=550|Corner.X=340|Corner.Y=550|LineWidth=1|Color=16711680
|RECORD=13|OwnerIndex=801|IsNotAccesible=T|IndexInSheet=21|OwnerPartId=1|Location.X=330|Location.Y=550|Corner.X=332|Corner.X_Frac=50000|Corner.Y=550|LineWidth=1|Color=16711680
|RECORD=13|OwnerIndex=801|IsNotAccesible=T|IndexInSheet=22|OwnerPartId=1|Location.X=337|Location.X_Frac=50000|Location.Y=555|Corner.X=337|Corner.X_Frac=50000|Corner.Y=545|LineWidth=1|Color=16711680
|RECORD=13|OwnerIndex=801|IsNotAccesible=T|IndexInSheet=23|OwnerPartId=1|Location.X=332|Location.X_Frac=50000|Location.Y=555|Corner.X=332|Corner.X_Frac=50000|Corner.Y=545|LineWidth=1|Color=16711680
|RECORD=41|OwnerIndex=801|IndexInSheet=24|OwnerPartId=-1|Location.X=318|Location.Y=556|Color=8388608|FontID=1|IsHidden=T|Text=<VALENTIUM>|Name=VALENTIUM PART NUM
|RECORD=34|OwnerIndex=801|IndexInSheet=-1|OwnerPartId=-1|Location.X=329|Location.Y=556|Color=8388608|FontID=3|Text=C4|Name=Designator|ReadOnlyState=1
|RECORD=41|OwnerIndex=801|IndexInSheet=-1|OwnerPartId=-1|Location.X=318|Location.Y=556|Color=8388608|FontID=2|IsHidden=T|Text=CAP_0603_0.01UF_50V|Name=Comment|ReadOnlyState=1
|RECORD=44|OwnerIndex=801
|RECORD=45|OwnerIndex=831|IndexInSheet=-1|Description=Chip Capacitor, 0603, 2-Leads, Body 1.60x0.80mm, IPC Medium Density|UseComponentLibrary=T|ModelName=CAPC1608X10N|ModelType=PCBLIB|DatafileCount=1|ModelDatafileEntity0=CAPC1608X10N|ModelDatafileKind0=PCBLib|IsCurrent=T|DatalinksLocked=T|DatabaseDatalinksLocked=T|IntegratedModel=T|DatabaseModel=T
|RECORD=46|OwnerIndex=832
|RECORD=48|OwnerIndex=832
|RECORD=1|LibReference=PM124SH-100M-RC|ComponentDescription=IND, PWR, 10.uH, 20%, 4A, 0.04DCR, 12.5X12.5MM, SHLD|PartCount=2|DisplayModeCount=1|IndexInSheet=68|OwnerPartId=-1|Location.X=370|Location.Y=460|CurrentPartId=1|LibraryPath=*|SourceLibraryName=Passives.IntLib|TargetFileName=*|AreaColor=11599871|Color=128|PartIDLocked=F|DesignItemId=PM124SH-100M-RC|AllPinCount=2
|RECORD=41|OwnerIndex=835|OwnerPartId=-1|Location.X=370|Location.Y=460|Color=8388608|FontID=2|IsHidden=T|Text=PM124SH-100M-RC|Name=MFG PART NUM
|RECORD=41|OwnerIndex=835|IndexInSheet=1|OwnerPartId=-1|Location.X=370|Location.Y=460|Color=8388608|FontID=2|IsHidden=T|Text=10/23/2013|Name=MODIFY DATE
|RECORD=41|OwnerIndex=835|IndexInSheet=2|OwnerPartId=-1|Location.X=370|Location.Y=460|Color=8388608|FontID=2|IsHidden=T|Text=BOURNS|Name=MFG NAME
|RECORD=41|OwnerIndex=835|IndexInSheet=3|OwnerPartId=-1|Location.X=368|Location.Y=482|Location.Y_Frac=10000|Color=8388608|FontID=2|IsHidden=T|Text=10/23/2013|Name=Date
|RECORD=41|OwnerIndex=835|IndexInSheet=4|OwnerPartId=-1|Location.X=368|Location.Y=482|Location.Y_Frac=10000|Color=8388608|FontID=2|IsHidden=T|Text=IND, PWR|Name=CATEGORY
|RECORD=41|OwnerIndex=835|IndexInSheet=5|OwnerPartId=-1|Location.X=368|Location.Y=488|Color=8388608|FontID=2|IsHidden=T|Text=125C|Name=MAXTEMP
|RECORD=41|OwnerIndex=835|IndexInSheet=6|OwnerPartId=-1|Location.X=368|Location.Y=488|Color=8388608|FontID=2|IsHidden=T|Text=-40C|Name=MINTEMP
|RECORD=41|OwnerIndex=835|IndexInSheet=7|OwnerPartId=-1|Location.X=368|Location.Y=488|Color=8388608|FontID=2|IsHidden=T|Text=SHLD|Name=OTHER
|RECORD=41|OwnerIndex=835|IndexInSheet=8|OwnerPartId=-1|Location.X=368|Location.Y=488|Color=8388608|FontID=2|IsHidden=T|Text=20%|Name=P1
|RECORD=41|OwnerIndex=835|IndexInSheet=9|OwnerPartId=-1|Location.X=368|Location.Y=488|Color=8388608|FontID=2|IsHidden=T|Text=4A|Name=P2
|RECORD=41|OwnerIndex=835|IndexInSheet=10|OwnerPartId=-1|Location.X=368|Location.Y=488|Color=8388608|FontID=2|IsHidden=T|Text=36mOhm|Name=P3
|RECORD=41|OwnerIndex=835|IndexInSheet=11|OwnerPartId=-1|Location.X=368|Location.Y=488|Color=8388608|FontID=2|IsHidden=T|Text=12.5X12.5MM|Name=SIZE
|RECORD=41|OwnerIndex=835|IndexInSheet=12|OwnerPartId=-1|Location.X=368|Location.Y=488|Color=8388608|FontID=2|IsHidden=T|Name=SUB
|RECORD=41|OwnerIndex=835|IndexInSheet=13|OwnerPartId=-1|Location.X=368|Location.Y=447|Color=8388608|FontID=1|IsHidden=T|Text=*|Name=SHEETPART
|RECORD=41|OwnerIndex=835|IndexInSheet=14|OwnerPartId=-1|Location.X=368|Location.Y=492|Color=8388608|FontID=1|IsHidden=T|Text=IND, PWR, 10.uH, 20%, 4A, 0.04DCR, 12.5X12.5MM, SHLD|Name=DESC
|RECORD=41|OwnerIndex=835|IndexInSheet=15|OwnerPartId=-1|Location.X=368|Location.Y=492|Color=8388608|FontID=1|IsHidden=T|Text=Digi-Key|Name=Supplier 1|ReadOnlyState=3
|RECORD=41|OwnerIndex=835|IndexInSheet=16|OwnerPartId=-1|Location.X=368|Location.Y=492|Color=8388608|FontID=1|IsHidden=T|Text=PM124SH-100M-RCCT-ND|Name=Supplier Part Number 1|ReadOnlyState=3
|RECORD=2|OwnerIndex=835|OwnerPartId=1|FormalType=1|Electrical=4|PinConglomerate=32|PinLength=20|Location.X=430|Location.Y=460|Designator=1|PinPropagationDelay=0.000000E+000
|RECORD=2|OwnerIndex=835|OwnerPartId=1|FormalType=1|Electrical=4|PinConglomerate=34|PinLength=20|Location.X=390|Location.Y=460|Designator=2|PinPropagationDelay=0.000000E+000
|RECORD=12|OwnerIndex=835|IsNotAccesible=T|IndexInSheet=19|OwnerPartId=1|Location.X=425|Location.Y=465|Radius=5|LineWidth=1|EndAngle=180.000|Color=16711680
|RECORD=12|OwnerIndex=835|IsNotAccesible=T|IndexInSheet=20|OwnerPartId=1|Location.X=415|Location.Y=465|Radius=5|LineWidth=1|EndAngle=180.000|Color=16711680
|RECORD=12|OwnerIndex=835|IsNotAccesible=T|IndexInSheet=21|OwnerPartId=1|Location.X=405|Location.Y=465|Radius=5|LineWidth=1|EndAngle=180.000|Color=16711680
|RECORD=12|OwnerIndex=835|IsNotAccesible=T|IndexInSheet=22|OwnerPartId=1|Location.X=395|Location.Y=465|Radius=5|LineWidth=1|EndAngle=180.000|Color=16711680
|RECORD=13|OwnerIndex=835|IsNotAccesible=T|IndexInSheet=23|OwnerPartId=1|Location.X=430|Location.Y=465|Corner.X=430|Corner.Y=460|LineWidth=1|Color=16711680
|RECORD=13|OwnerIndex=835|IsNotAccesible=T|IndexInSheet=24|OwnerPartId=1|Location.X=420|Location.Y=465|Corner.X=420|Corner.Y=460|LineWidth=1|Color=16711680
|RECORD=13|OwnerIndex=835|IsNotAccesible=T|IndexInSheet=25|OwnerPartId=1|Location.X=410|Location.Y=465|Corner.X=410|Corner.Y=460|LineWidth=1|Color=16711680
|RECORD=13|OwnerIndex=835|IsNotAccesible=T|IndexInSheet=26|OwnerPartId=1|Location.X=400|Location.Y=465|Corner.X=400|Corner.Y=460|LineWidth=1|Color=16711680
|RECORD=13|OwnerIndex=835|IsNotAccesible=T|IndexInSheet=27|OwnerPartId=1|Location.X=390|Location.Y=465|Corner.X=390|Corner.Y=460|LineWidth=1|Color=16711680
|RECORD=41|OwnerIndex=835|IndexInSheet=28|OwnerPartId=-1|Location.X=389|Location.Y=445|Color=8388608|FontID=2|Text=10.uH|Name=VALUE
|RECORD=41|OwnerIndex=835|IndexInSheet=29|OwnerPartId=-1|Location.X=368|Location.Y=492|Color=8388608|FontID=1|IsHidden=T|Text=<VALENTIUM>|Name=VALENTIUM PART NUM
|RECORD=34|OwnerIndex=835|IndexInSheet=-1|OwnerPartId=-1|Location.X=389|Location.Y=470|Color=8388608|FontID=3|Text=L1|Name=Designator|ReadOnlyState=1
|RECORD=41|OwnerIndex=835|IndexInSheet=-1|OwnerPartId=-1|Location.X=370|Location.Y=460|Color=8388608|FontID=2|IsHidden=T|Text=PM124SH-100M-RC|Name=Comment
|RECORD=44|OwnerIndex=835
|RECORD=45|OwnerIndex=870|IndexInSheet=-1|Description=Footprint not found|UseComponentLibrary=T|ModelName=IND_PM124SH|ModelType=PCBLIB|DatafileCount=1|ModelDatafileEntity0=IND_PM124SH|ModelDatafileKind0=PCBLib|IsCurrent=T|DatalinksLocked=T|DatabaseDatalinksLocked=T|IntegratedModel=T|DatabaseModel=T
|RECORD=46|OwnerIndex=871
|RECORD=48|OwnerIndex=871
|RECORD=1|LibReference=PM124SH-100M-RC|ComponentDescription=IND, PWR, 10.uH, 20%, 4A, 0.04DCR, 12.5X12.5MM, SHLD|PartCount=2|DisplayModeCount=1|IndexInSheet=69|OwnerPartId=-1|Location.X=1140|Location.Y=460|CurrentPartId=1|LibraryPath=*|SourceLibraryName=Passives.IntLib|TargetFileName=*|AreaColor=11599871|Color=128|PartIDLocked=F|DesignItemId=PM124SH-100M-RC|AllPinCount=2
|RECORD=41|OwnerIndex=874|OwnerPartId=-1|Location.X=1140|Location.Y=460|Color=8388608|FontID=2|IsHidden=T|Text=PM124SH-100M-RC|Name=MFG PART NUM
|RECORD=41|OwnerIndex=874|IndexInSheet=1|OwnerPartId=-1|Location.X=1140|Location.Y=460|Color=8388608|FontID=2|IsHidden=T|Text=10/23/2013|Name=MODIFY DATE
|RECORD=41|OwnerIndex=874|IndexInSheet=2|OwnerPartId=-1|Location.X=1140|Location.Y=460|Color=8388608|FontID=2|IsHidden=T|Text=BOURNS|Name=MFG NAME
|RECORD=41|OwnerIndex=874|IndexInSheet=3|OwnerPartId=-1|Location.X=1138|Location.Y=482|Location.Y_Frac=10000|Color=8388608|FontID=2|IsHidden=T|Text=10/23/2013|Name=Date
|RECORD=41|OwnerIndex=874|IndexInSheet=4|OwnerPartId=-1|Location.X=1138|Location.Y=482|Location.Y_Frac=10000|Color=8388608|FontID=2|IsHidden=T|Text=IND, PWR|Name=CATEGORY
|RECORD=41|OwnerIndex=874|IndexInSheet=5|OwnerPartId=-1|Location.X=1138|Location.Y=488|Color=8388608|FontID=2|IsHidden=T|Text=125C|Name=MAXTEMP
|RECORD=41|OwnerIndex=874|IndexInSheet=6|OwnerPartId=-1|Location.X=1138|Location.Y=488|Color=8388608|FontID=2|IsHidden=T|Text=-40C|Name=MINTEMP
|RECORD=41|OwnerIndex=874|IndexInSheet=7|OwnerPartId=-1|Location.X=1138|Location.Y=488|Color=8388608|FontID=2|IsHidden=T|Text=SHLD|Name=OTHER
|RECORD=41|OwnerIndex=874|IndexInSheet=8|OwnerPartId=-1|Location.X=1138|Location.Y=488|Color=8388608|FontID=2|IsHidden=T|Text=20%|Name=P1
|RECORD=41|OwnerIndex=874|IndexInSheet=9|OwnerPartId=-1|Location.X=1138|Location.Y=488|Color=8388608|FontID=2|IsHidden=T|Text=4A|Name=P2
|RECORD=41|OwnerIndex=874|IndexInSheet=10|OwnerPartId=-1|Location.X=1138|Location.Y=488|Color=8388608|FontID=2|IsHidden=T|Text=36mOhm|Name=P3
|RECORD=41|OwnerIndex=874|IndexInSheet=11|OwnerPartId=-1|Location.X=1138|Location.Y=488|Color=8388608|FontID=2|IsHidden=T|Text=12.5X12.5MM|Name=SIZE
|RECORD=41|OwnerIndex=874|IndexInSheet=12|OwnerPartId=-1|Location.X=1138|Location.Y=488|Color=8388608|FontID=2|IsHidden=T|Name=SUB
|RECORD=41|OwnerIndex=874|IndexInSheet=13|OwnerPartId=-1|Location.X=1138|Location.Y=447|Color=8388608|FontID=1|IsHidden=T|Text=*|Name=SHEETPART
|RECORD=41|OwnerIndex=874|IndexInSheet=14|OwnerPartId=-1|Location.X=1138|Location.Y=492|Color=8388608|FontID=1|IsHidden=T|Text=IND, PWR, 10.uH, 20%, 4A, 0.04DCR, 12.5X12.5MM, SHLD|Name=DESC
|RECORD=41|OwnerIndex=874|IndexInSheet=15|OwnerPartId=-1|Location.X=1138|Location.Y=492|Color=8388608|FontID=1|IsHidden=T|Text=Digi-Key|Name=Supplier 1|ReadOnlyState=3
|RECORD=41|OwnerIndex=874|IndexInSheet=16|OwnerPartId=-1|Location.X=1138|Location.Y=492|Color=8388608|FontID=1|IsHidden=T|Text=PM124SH-100M-RCCT-ND|Name=Supplier Part Number 1|ReadOnlyState=3
|RECORD=2|OwnerIndex=874|OwnerPartId=1|FormalType=1|Electrical=4|PinConglomerate=32|PinLength=20|Location.X=1200|Location.Y=460|Designator=1|PinPropagationDelay=0.000000E+000
|RECORD=2|OwnerIndex=874|OwnerPartId=1|FormalType=1|Electrical=4|PinConglomerate=34|PinLength=20|Location.X=1160|Location.Y=460|Designator=2|PinPropagationDelay=0.000000E+000
|RECORD=12|OwnerIndex=874|IsNotAccesible=T|IndexInSheet=19|OwnerPartId=1|Location.X=1195|Location.Y=465|Radius=5|LineWidth=1|EndAngle=180.000|Color=16711680
|RECORD=12|OwnerIndex=874|IsNotAccesible=T|IndexInSheet=20|OwnerPartId=1|Location.X=1185|Location.Y=465|Radius=5|LineWidth=1|EndAngle=180.000|Color=16711680
|RECORD=12|OwnerIndex=874|IsNotAccesible=T|IndexInSheet=21|OwnerPartId=1|Location.X=1175|Location.Y=465|Radius=5|LineWidth=1|EndAngle=180.000|Color=16711680
|RECORD=12|OwnerIndex=874|IsNotAccesible=T|IndexInSheet=22|OwnerPartId=1|Location.X=1165|Location.Y=465|Radius=5|LineWidth=1|EndAngle=180.000|Color=16711680
|RECORD=13|OwnerIndex=874|IsNotAccesible=T|IndexInSheet=23|OwnerPartId=1|Location.X=1200|Location.Y=465|Corner.X=1200|Corner.Y=460|LineWidth=1|Color=16711680
|RECORD=13|OwnerIndex=874|IsNotAccesible=T|IndexInSheet=24|OwnerPartId=1|Location.X=1190|Location.Y=465|Corner.X=1190|Corner.Y=460|LineWidth=1|Color=16711680
|RECORD=13|OwnerIndex=874|IsNotAccesible=T|IndexInSheet=25|OwnerPartId=1|Location.X=1180|Location.Y=465|Corner.X=1180|Corner.Y=460|LineWidth=1|Color=16711680
|RECORD=13|OwnerIndex=874|IsNotAccesible=T|IndexInSheet=26|OwnerPartId=1|Location.X=1170|Location.Y=465|Corner.X=1170|Corner.Y=460|LineWidth=1|Color=16711680
|RECORD=13|OwnerIndex=874|IsNotAccesible=T|IndexInSheet=27|OwnerPartId=1|Location.X=1160|Location.Y=465|Corner.X=1160|Corner.Y=460|LineWidth=1|Color=16711680
|RECORD=41|OwnerIndex=874|IndexInSheet=28|OwnerPartId=-1|Location.X=1159|Location.Y=445|Color=8388608|FontID=2|Text=10.uH|Name=VALUE
|RECORD=41|OwnerIndex=874|IndexInSheet=29|OwnerPartId=-1|Location.X=1138|Location.Y=492|Color=8388608|FontID=1|IsHidden=T|Text=<VALENTIUM>|Name=VALENTIUM PART NUM
|RECORD=34|OwnerIndex=874|IndexInSheet=-1|OwnerPartId=-1|Location.X=1159|Location.Y=470|Color=8388608|FontID=3|Text=L2|Name=Designator|ReadOnlyState=1
|RECORD=41|OwnerIndex=874|IndexInSheet=-1|OwnerPartId=-1|Location.X=1140|Location.Y=460|Color=8388608|FontID=2|IsHidden=T|Text=PM124SH-100M-RC|Name=Comment
|RECORD=44|OwnerIndex=874
|RECORD=45|OwnerIndex=909|IndexInSheet=-1|Description=Footprint not found|UseComponentLibrary=T|ModelName=IND_PM124SH|ModelType=PCBLIB|DatafileCount=1|ModelDatafileEntity0=IND_PM124SH|ModelDatafileKind0=PCBLib|IsCurrent=T|DatalinksLocked=T|DatabaseDatalinksLocked=T|IntegratedModel=T|DatabaseModel=T
|RECORD=46|OwnerIndex=910
|RECORD=48|OwnerIndex=910
|RECORD=1|LibReference=CAP_0603_0.01UF_50V|ComponentDescription=CAP, CER, 0.01UF, 50V, 10%, X7R, 0603|PartCount=2|DisplayModeCount=1|IndexInSheet=70|OwnerPartId=-1|Location.X=1090|Location.Y=540|Orientation=1|CurrentPartId=1|LibraryPath=*|SourceLibraryName=Capacitors.IntLib|TargetFileName=*|AreaColor=11599871|Color=128|PartIDLocked=F|DesignItemId=CAP_0603_0.01UF_50V|AllPinCount=2
|RECORD=41|OwnerIndex=913|OwnerPartId=-1|Location.X=1038|Location.Y=566|Color=8388608|FontID=2|IsHidden=T|Text=CAP, CER|Name=CATEGORY
|RECORD=41|OwnerIndex=913|IndexInSheet=1|OwnerPartId=-1|Location.X=1038|Location.Y=566|Color=8388608|FontID=2|IsHidden=T|Text=KEMET|Name=MFG NAME
|RECORD=41|OwnerIndex=913|IndexInSheet=2|OwnerPartId=-1|Location.X=1038|Location.Y=566|Color=8388608|FontID=2|IsHidden=T|Text=C0603C103K5RACTU|Name=MFG PART NUM
|RECORD=41|OwnerIndex=913|IndexInSheet=3|OwnerPartId=-1|Location.X=1038|Location.Y=566|Color=8388608|FontID=2|IsHidden=T|Text=10/23/2013|Name=MODIFY DATE
|RECORD=41|OwnerIndex=913|IndexInSheet=4|OwnerPartId=-1|Location.X=1038|Location.Y=566|Color=8388608|FontID=2|IsHidden=T|Text=7/24/2013|Name=Date
|RECORD=41|OwnerIndex=913|IndexInSheet=5|OwnerPartId=-1|Location.X=1038|Location.Y=566|Color=8388608|FontID=2|IsHidden=T|Text=*|Name=SHEETPART
|RECORD=41|OwnerIndex=913|IndexInSheet=6|OwnerPartId=-1|Location.X=1038|Location.Y=566|Color=8388608|FontID=2|IsHidden=T|Text=10%|Name=P1
|RECORD=41|OwnerIndex=913|IndexInSheet=7|OwnerPartId=-1|Location.X=1038|Location.Y=566|Color=8388608|FontID=2|IsHidden=T|Text=125C|Name=MAXTEMP
|RECORD=41|OwnerIndex=913|IndexInSheet=8|OwnerPartId=-1|Location.X=1038|Location.Y=566|Color=8388608|FontID=2|IsHidden=T|Text=-55C|Name=MINTEMP
|RECORD=41|OwnerIndex=913|IndexInSheet=9|OwnerPartId=-1|Location.X=1038|Location.Y=566|Color=8388608|FontID=2|IsHidden=T|Name=OTHER
|RECORD=41|OwnerIndex=913|IndexInSheet=10|OwnerPartId=-1|Location.X=1038|Location.Y=566|Color=8388608|FontID=2|IsHidden=T|Text=50V|Name=P2
|RECORD=41|OwnerIndex=913|IndexInSheet=11|OwnerPartId=-1|Location.X=1038|Location.Y=566|Color=8388608|FontID=2|IsHidden=T|Text=X7R|Name=P3
|RECORD=41|OwnerIndex=913|IndexInSheet=12|OwnerPartId=-1|Location.X=1038|Location.Y=566|Color=8388608|FontID=2|IsHidden=T|Text=0603|Name=Size
|RECORD=41|OwnerIndex=913|IndexInSheet=13|OwnerPartId=-1|Location.X=1038|Location.Y=566|Color=8388608|FontID=2|IsHidden=T|Name=SUB
|RECORD=41|OwnerIndex=913|IndexInSheet=14|OwnerPartId=-1|Location.X=1038|Location.Y=566|Color=8388608|FontID=2|IsHidden=T|Text=Digi-Key|Name=Supplier 1|ReadOnlyState=3
|RECORD=41|OwnerIndex=913|IndexInSheet=15|OwnerPartId=-1|Location.X=1038|Location.Y=566|Color=8388608|FontID=2|IsHidden=T|Text=399-1091-1-ND|Name=Supplier Part Number 1|ReadOnlyState=3
|RECORD=41|OwnerIndex=913|IndexInSheet=16|OwnerPartId=-1|Location.X=1038|Location.Y=566|Color=8388608|FontID=1|IsHidden=T|Text=CAP, CER, 0.01UF, 50V, 10%, X7R, 0603|Name=DESC
|RECORD=41|OwnerIndex=913|IndexInSheet=17|OwnerPartId=-1|Location.X=1049|Location.Y=542|Color=8388608|FontID=2|Text=0.01uF|Name=VALUE
|RECORD=2|OwnerIndex=913|OwnerPartId=1|FormalType=1|Electrical=4|PinConglomerate=32|PinLength=10|Location.X=1060|Location.Y=560|Name=2|Designator=2|SwapIdPin=2|SwapIDPart=1|PinPropagationDelay=0.000000E+000
|RECORD=2|OwnerIndex=913|OwnerPartId=1|FormalType=1|Electrical=4|PinConglomerate=34|PinLength=10|Location.X=1050|Location.Y=560|Name=1|Designator=1|SwapIdPin=1|SwapIDPart=1|PinPropagationDelay=0.000000E+000
|RECORD=13|OwnerIndex=913|IsNotAccesible=T|IndexInSheet=20|OwnerPartId=1|Location.X=1057|Location.X_Frac=50000|Location.Y=560|Corner.X=1060|Corner.Y=560|LineWidth=1|Color=16711680
|RECORD=13|OwnerIndex=913|IsNotAccesible=T|IndexInSheet=21|OwnerPartId=1|Location.X=1050|Location.Y=560|Corner.X=1052|Corner.X_Frac=50000|Corner.Y=560|LineWidth=1|Color=16711680
|RECORD=13|OwnerIndex=913|IsNotAccesible=T|IndexInSheet=22|OwnerPartId=1|Location.X=1057|Location.X_Frac=50000|Location.Y=565|Corner.X=1057|Corner.X_Frac=50000|Corner.Y=555|LineWidth=1|Color=16711680
|RECORD=13|OwnerIndex=913|IsNotAccesible=T|IndexInSheet=23|OwnerPartId=1|Location.X=1052|Location.X_Frac=50000|Location.Y=565|Corner.X=1052|Corner.X_Frac=50000|Corner.Y=555|LineWidth=1|Color=16711680
|RECORD=41|OwnerIndex=913|IndexInSheet=24|OwnerPartId=-1|Location.X=1038|Location.Y=566|Color=8388608|FontID=1|IsHidden=T|Text=<VALENTIUM>|Name=VALENTIUM PART NUM
|RECORD=34|OwnerIndex=913|IndexInSheet=-1|OwnerPartId=-1|Location.X=1049|Location.Y=566|Color=8388608|FontID=3|Text=C3|Name=Designator|ReadOnlyState=1
|RECORD=41|OwnerIndex=913|IndexInSheet=-1|OwnerPartId=-1|Location.X=1038|Location.Y=566|Color=8388608|FontID=2|IsHidden=T|Text=CAP_0603_0.01UF_50V|Name=Comment|ReadOnlyState=1
|RECORD=44|OwnerIndex=913
|RECORD=45|OwnerIndex=943|IndexInSheet=-1|Description=Chip Capacitor, 0603, 2-Leads, Body 1.60x0.80mm, IPC Medium Density|UseComponentLibrary=T|ModelName=CAPC1608X10N|ModelType=PCBLIB|DatafileCount=1|ModelDatafileEntity0=CAPC1608X10N|ModelDatafileKind0=PCBLib|IsCurrent=T|DatalinksLocked=T|DatabaseDatalinksLocked=T|IntegratedModel=T|DatabaseModel=T
|RECORD=46|OwnerIndex=944
|RECORD=48|OwnerIndex=944
|RECORD=1|LibReference=RES_0603_47K|ComponentDescription=RES, 47K, 1%, 1/10W, TF, 0603|PartCount=2|DisplayModeCount=1|IndexInSheet=71|OwnerPartId=-1|Location.X=880|Location.Y=490|Orientation=1|CurrentPartId=1|LibraryPath=*|SourceLibraryName=Resistors.IntLib|TargetFileName=*|AreaColor=11599871|Color=128|PartIDLocked=F|DesignItemId=RES_0603_47K|AllPinCount=2
|RECORD=41|OwnerIndex=947|OwnerPartId=-1|Location.X=876|Location.Y=542|Color=8388608|FontID=2|IsHidden=T|Text=1/22/2014|Name=ModifyDate
|RECORD=41|OwnerIndex=947|IndexInSheet=1|OwnerPartId=-1|Location.X=876|Location.Y=542|Color=8388608|FontID=2|IsHidden=T|Text=ERJ-3EKF4702V|Name=MFG PART NUM
|RECORD=41|OwnerIndex=947|IndexInSheet=2|OwnerPartId=-1|Location.X=876|Location.Y=542|Color=8388608|FontID=2|IsHidden=T|Text=PANASONIC|Name=MFG NAME
|RECORD=41|OwnerIndex=947|IndexInSheet=3|OwnerPartId=-1|Location.X=876|Location.Y=542|Color=8388608|FontID=2|IsHidden=T|Text=RES|Name=CATEGORY
|RECORD=41|OwnerIndex=947|IndexInSheet=4|OwnerPartId=-1|Location.X=876|Location.Y=542|Color=8388608|FontID=2|IsHidden=T|Text=1/22/2014|Name=Date
|RECORD=41|OwnerIndex=947|IndexInSheet=5|OwnerPartId=-1|Location.X=876|Location.Y=542|Color=8388608|FontID=2|IsHidden=T|Text=1%|Name=P1
|RECORD=41|OwnerIndex=947|IndexInSheet=6|OwnerPartId=-1|Location.X=876|Location.Y=542|Color=8388608|FontID=2|IsHidden=T|Text=TF|Name=P3
|RECORD=41|OwnerIndex=947|IndexInSheet=7|OwnerPartId=-1|Location.X=876|Location.Y=542|Color=8388608|FontID=2|IsHidden=T|Text=1/10W|Name=P2
|RECORD=41|OwnerIndex=947|IndexInSheet=8|OwnerPartId=-1|Location.X=876|Location.Y=542|Color=8388608|FontID=2|IsHidden=T|Text=125C|Name=MAXTEMP
|RECORD=41|OwnerIndex=947|IndexInSheet=9|OwnerPartId=-1|Location.X=876|Location.Y=542|Color=8388608|FontID=2|IsHidden=T|Text=-55C|Name=MINTEMP
|RECORD=41|OwnerIndex=947|IndexInSheet=10|OwnerPartId=-1|Location.X=876|Location.Y=542|Color=8388608|FontID=2|IsHidden=T|Text=100PPM|Name=OTHER
|RECORD=41|OwnerIndex=947|IndexInSheet=11|OwnerPartId=-1|Location.X=876|Location.Y=542|Color=8388608|FontID=2|IsHidden=T|Text=0603|Name=SIZE
|RECORD=41|OwnerIndex=947|IndexInSheet=12|OwnerPartId=-1|Location.X=876|Location.Y=542|Color=8388608|FontID=2|IsHidden=T|Text=GENERIC|Name=SUB
|RECORD=41|OwnerIndex=947|IndexInSheet=13|OwnerPartId=-1|Location.X=876|Location.Y=542|Color=8388608|FontID=1|IsHidden=T|Text=*|Name=SHEETPART
|RECORD=41|OwnerIndex=947|IndexInSheet=14|OwnerPartId=-1|Location.X=876|Location.Y=542|Color=8388608|FontID=1|IsHidden=T|Text=RES, 47K, 1%, 1/10W, TF, 0603|Name=DESC
|RECORD=41|OwnerIndex=947|IndexInSheet=15|OwnerPartId=-1|Location.X=876|Location.Y=542|Color=8388608|FontID=1|IsHidden=T|Text=Digi-Key|Name=Supplier 1|ReadOnlyState=3
|RECORD=41|OwnerIndex=947|IndexInSheet=16|OwnerPartId=-1|Location.X=876|Location.Y=542|Color=8388608|FontID=1|IsHidden=T|Text=P47.0KHCT-ND|Name=Supplier Part Number 1|ReadOnlyState=3
|RECORD=41|OwnerIndex=947|IndexInSheet=17|OwnerPartId=-1|Location.X=884|Location.Y=505|Color=8388608|FontID=2|Text=47K|Name=VALUE
|RECORD=2|OwnerIndex=947|OwnerPartId=1|FormalType=1|Electrical=4|PinConglomerate=35|PinLength=10|Location.X=880|Location.Y=500|Name=1|Designator=1|PinPropagationDelay=0.000000E+000
|RECORD=2|OwnerIndex=947|OwnerPartId=1|FormalType=1|Electrical=4|PinConglomerate=33|PinLength=10|Location.X=880|Location.Y=530|Name=2|Designator=2|PinPropagationDelay=0.000000E+000
|RECORD=6|OwnerIndex=947|IsNotAccesible=T|IndexInSheet=20|OwnerPartId=1|LineWidth=1|Color=16711680|LocationCount=7|X1=880|Y1=530|X2=877|Y2=527|X3=883|Y3=521|X4=877|Y4=515|X5=883|Y5=509|X6=877|Y6=503|X7=880|Y7=500
|RECORD=41|OwnerIndex=947|IndexInSheet=21|OwnerPartId=-1|Location.X=876|Location.Y=542|Color=8388608|FontID=1|IsHidden=T|Text=<VELENTIUM>|Name=VELENTIUM PART NUM
|RECORD=34|OwnerIndex=947|IndexInSheet=-1|OwnerPartId=-1|Location.X=884|Location.Y=517|Color=8388608|FontID=3|Text=R3|Name=Designator|ReadOnlyState=1
|RECORD=41|OwnerIndex=947|IndexInSheet=-1|OwnerPartId=-1|Location.X=876|Location.Y=542|Color=8388608|FontID=2|IsHidden=T|Text==MFG PART NUM|Name=Comment
|RECORD=44|OwnerIndex=947
|RECORD=45|OwnerIndex=974|IndexInSheet=-1|Description=Chip Resistor, 0603, 2-Leads, Body 1.57x0.85mm, IPC Medium Density|UseComponentLibrary=T|ModelName=RESC1608X50N|ModelType=PCBLIB|DatafileCount=1|ModelDatafileEntity0=RESC1608X50N|ModelDatafileKind0=PCBLib|IsCurrent=T|DatalinksLocked=T|DatabaseDatalinksLocked=T|IntegratedModel=T|DatabaseModel=T
|RECORD=46|OwnerIndex=975
|RECORD=48|OwnerIndex=975
|RECORD=1|LibReference=RES_0603_10K|ComponentDescription=RES, 10K, 1%, 1/10W, TF, 0603|PartCount=2|DisplayModeCount=1|IndexInSheet=72|OwnerPartId=-1|Location.X=1100|Location.Y=310|Orientation=1|CurrentPartId=1|LibraryPath=*|SourceLibraryName=Resistors.IntLib|TargetFileName=*|AreaColor=11599871|Color=128|PartIDLocked=F|DesignItemId=RES_0603_10K|AllPinCount=2
|RECORD=41|OwnerIndex=978|OwnerPartId=-1|Location.X=1096|Location.Y=362|Color=8388608|FontID=2|IsHidden=T|Text=7/25/2013|Name=ModifyDate
|RECORD=41|OwnerIndex=978|IndexInSheet=1|OwnerPartId=-1|Location.X=1096|Location.Y=362|Color=8388608|FontID=2|IsHidden=T|Text=ERJ-3EKF1002V|Name=MFG PART NUM
|RECORD=41|OwnerIndex=978|IndexInSheet=2|OwnerPartId=-1|Location.X=1096|Location.Y=362|Color=8388608|FontID=2|IsHidden=T|Text=PANASONIC|Name=MFG NAME
|RECORD=41|OwnerIndex=978|IndexInSheet=3|OwnerPartId=-1|Location.X=1096|Location.Y=362|Color=8388608|FontID=2|IsHidden=T|Text=RES|Name=CATEGORY
|RECORD=41|OwnerIndex=978|IndexInSheet=4|OwnerPartId=-1|Location.X=1096|Location.Y=362|Color=8388608|FontID=2|IsHidden=T|Text=7/26/2013|Name=Date
|RECORD=41|OwnerIndex=978|IndexInSheet=5|OwnerPartId=-1|Location.X=1096|Location.Y=362|Color=8388608|FontID=2|IsHidden=T|Text=1%|Name=P1
|RECORD=41|OwnerIndex=978|IndexInSheet=6|OwnerPartId=-1|Location.X=1096|Location.Y=362|Color=8388608|FontID=2|IsHidden=T|Text=TF|Name=P3
|RECORD=41|OwnerIndex=978|IndexInSheet=7|OwnerPartId=-1|Location.X=1096|Location.Y=362|Color=8388608|FontID=2|IsHidden=T|Text=1/10W|Name=P2
|RECORD=41|OwnerIndex=978|IndexInSheet=8|OwnerPartId=-1|Location.X=1096|Location.Y=362|Color=8388608|FontID=2|IsHidden=T|Text=125C|Name=MAXTEMP
|RECORD=41|OwnerIndex=978|IndexInSheet=9|OwnerPartId=-1|Location.X=1096|Location.Y=362|Color=8388608|FontID=2|IsHidden=T|Text=-55C|Name=MINTEMP
|RECORD=41|OwnerIndex=978|IndexInSheet=10|OwnerPartId=-1|Location.X=1096|Location.Y=362|Color=8388608|FontID=2|IsHidden=T|Text=100PPM|Name=OTHER
|RECORD=41|OwnerIndex=978|IndexInSheet=11|OwnerPartId=-1|Location.X=1096|Location.Y=362|Color=8388608|FontID=2|IsHidden=T|Text=0603|Name=SIZE
|RECORD=41|OwnerIndex=978|IndexInSheet=12|OwnerPartId=-1|Location.X=1096|Location.Y=362|Color=8388608|FontID=2|IsHidden=T|Text=GENERIC|Name=SUB
|RECORD=41|OwnerIndex=978|IndexInSheet=13|OwnerPartId=-1|Location.X=1096|Location.Y=362|Color=8388608|FontID=2|IsHidden=T|Text=Digi-Key|Name=Supplier 1|ReadOnlyState=3
|RECORD=41|OwnerIndex=978|IndexInSheet=14|OwnerPartId=-1|Location.X=1096|Location.Y=362|Color=8388608|FontID=2|IsHidden=T|Text=P10.0KHCT-ND|Name=Supplier Part Number 1|ReadOnlyState=3
|RECORD=41|OwnerIndex=978|IndexInSheet=15|OwnerPartId=-1|Location.X=1096|Location.Y=362|Color=8388608|FontID=1|IsHidden=T|Text=*|Name=SHEETPART
|RECORD=41|OwnerIndex=978|IndexInSheet=16|OwnerPartId=-1|Location.X=1096|Location.Y=362|Color=8388608|FontID=1|IsHidden=T|Text=RES, 10K, 1%, 1/10W, TF, 0603|Name=DESC
|RECORD=41|OwnerIndex=978|IndexInSheet=17|OwnerPartId=-1|Location.X=1104|Location.Y=325|Color=8388608|FontID=2|Text=10K|Name=VALUE
|RECORD=2|OwnerIndex=978|OwnerPartId=1|FormalType=1|Electrical=4|PinConglomerate=35|PinLength=10|Location.X=1100|Location.Y=320|Name=1|Designator=1|PinPropagationDelay=0.000000E+000
|RECORD=2|OwnerIndex=978|OwnerPartId=1|FormalType=1|Electrical=4|PinConglomerate=33|PinLength=10|Location.X=1100|Location.Y=350|Name=2|Designator=2|PinPropagationDelay=0.000000E+000
|RECORD=6|OwnerIndex=978|IsNotAccesible=T|IndexInSheet=20|OwnerPartId=1|LineWidth=1|Color=16711680|LocationCount=7|X1=1100|Y1=350|X2=1097|Y2=347|X3=1103|Y3=341|X4=1097|Y4=335|X5=1103|Y5=329|X6=1097|Y6=323|X7=1100|Y7=320
|RECORD=41|OwnerIndex=978|IndexInSheet=21|OwnerPartId=-1|Location.X=1096|Location.Y=362|Color=8388608|FontID=1|IsHidden=T|Text=<VELENTIUM>|Name=VELENTIUM PART NUM
|RECORD=34|OwnerIndex=978|IndexInSheet=-1|OwnerPartId=-1|Location.X=1104|Location.Y=337|Color=8388608|FontID=3|Text=R7|Name=Designator|ReadOnlyState=1
|RECORD=41|OwnerIndex=978|IndexInSheet=-1|OwnerPartId=-1|Location.X=1096|Location.Y=362|Color=8388608|FontID=2|IsHidden=T|Text==MFG PART NUM|Name=Comment
|RECORD=44|OwnerIndex=978
|RECORD=45|OwnerIndex=1005|IndexInSheet=-1|Description=Chip Resistor, 0603, 2-Leads, Body 1.57x0.85mm, IPC Medium Density|UseComponentLibrary=T|ModelName=RESC1608X50N|ModelType=PCBLIB|DatafileCount=1|ModelDatafileEntity0=RESC1608X50N|ModelDatafileKind0=PCBLib|IsCurrent=T|DatalinksLocked=T|DatabaseDatalinksLocked=T|IntegratedModel=T|DatabaseModel=T
|RECORD=46|OwnerIndex=1006
|RECORD=48|OwnerIndex=1006
|RECORD=1|LibReference=RES_0603_2.2K|ComponentDescription=RES, 2.2K, 1%, 1/10W, TF, 0603|PartCount=2|DisplayModeCount=1|IndexInSheet=73|OwnerPartId=-1|Location.X=960|Location.Y=280|CurrentPartId=1|LibraryPath=*|SourceLibraryName=Resistors.IntLib|TargetFileName=*|AreaColor=11599871|Color=128|PartIDLocked=F|DesignItemId=RES_0603_2.2K|AllPinCount=2
|RECORD=41|OwnerIndex=1009|OwnerPartId=-1|Location.X=960|Location.Y=280|Color=8388608|FontID=2|IsHidden=T|Text=8/15/2013|Name=ModifyDate
|RECORD=41|OwnerIndex=1009|IndexInSheet=1|OwnerPartId=-1|Location.X=960|Location.Y=280|Color=8388608|FontID=2|IsHidden=T|Text=ERJ-3EKF2201V|Name=MFG PART NUM
|RECORD=41|OwnerIndex=1009|IndexInSheet=2|OwnerPartId=-1|Location.X=960|Location.Y=280|Color=8388608|FontID=2|IsHidden=T|Text=PANASONIC|Name=MFG NAME
|RECORD=41|OwnerIndex=1009|IndexInSheet=3|OwnerPartId=-1|Location.X=960|Location.Y=280|Color=8388608|FontID=2|IsHidden=T|Text=RES|Name=CATEGORY
|RECORD=41|OwnerIndex=1009|IndexInSheet=4|OwnerPartId=-1|Location.X=958|Location.Y=290|Color=8388608|FontID=2|IsHidden=T|Text=8/15/2013|Name=Date
|RECORD=41|OwnerIndex=1009|IndexInSheet=5|OwnerPartId=-1|Location.X=950|Location.X_Frac=55769|Location.Y=290|Color=8388608|FontID=2|IsHidden=T|Text=1%|Name=P1
|RECORD=41|OwnerIndex=1009|IndexInSheet=6|OwnerPartId=-1|Location.X=950|Location.X_Frac=55769|Location.Y=290|Color=8388608|FontID=2|IsHidden=T|Text=TF|Name=P3
|RECORD=41|OwnerIndex=1009|IndexInSheet=7|OwnerPartId=-1|Location.X=950|Location.X_Frac=55769|Location.Y=290|Color=8388608|FontID=2|IsHidden=T|Text=1/10W|Name=P2
|RECORD=41|OwnerIndex=1009|IndexInSheet=8|OwnerPartId=-1|Location.X=950|Location.X_Frac=55769|Location.Y=290|Color=8388608|FontID=2|IsHidden=T|Text=125C|Name=MAXTEMP
|RECORD=41|OwnerIndex=1009|IndexInSheet=9|OwnerPartId=-1|Location.X=950|Location.X_Frac=55769|Location.Y=290|Color=8388608|FontID=2|IsHidden=T|Text=-55C|Name=MINTEMP
|RECORD=41|OwnerIndex=1009|IndexInSheet=10|OwnerPartId=-1|Location.X=950|Location.X_Frac=55769|Location.Y=290|Color=8388608|FontID=2|IsHidden=T|Text=100PPM|Name=OTHER
|RECORD=41|OwnerIndex=1009|IndexInSheet=11|OwnerPartId=-1|Location.X=950|Location.X_Frac=55769|Location.Y=290|Color=8388608|FontID=2|IsHidden=T|Text=0603|Name=SIZE
|RECORD=41|OwnerIndex=1009|IndexInSheet=12|OwnerPartId=-1|Location.X=950|Location.X_Frac=55769|Location.Y=290|Color=8388608|FontID=2|IsHidden=T|Text=GENERIC|Name=SUB
|RECORD=41|OwnerIndex=1009|IndexInSheet=13|OwnerPartId=-1|Location.X=945|Location.X_Frac=98077|Location.Y=294|Color=8388608|FontID=2|IsHidden=T|Text=Digi-Key|Name=Supplier 1|ReadOnlyState=3
|RECORD=41|OwnerIndex=1009|IndexInSheet=14|OwnerPartId=-1|Location.X=945|Location.X_Frac=98077|Location.Y=294|Color=8388608|FontID=2|IsHidden=T|Text=P2.20KHCT-ND|Name=Supplier Part Number 1|ReadOnlyState=3
|RECORD=41|OwnerIndex=1009|IndexInSheet=15|OwnerPartId=-1|Location.X=945|Location.X_Frac=98077|Location.Y=266|Color=8388608|FontID=1|IsHidden=T|Text=*|Name=SHEETPART
|RECORD=41|OwnerIndex=1009|IndexInSheet=16|OwnerPartId=-1|Location.X=945|Location.X_Frac=98077|Location.Y=294|Color=8388608|FontID=1|IsHidden=T|Text=RES, 2.2K, 1%, 1/10W, TF, 0603|Name=DESC
|RECORD=41|OwnerIndex=1009|IndexInSheet=17|OwnerPartId=-1|Location.X=969|Location.Y=264|Color=8388608|FontID=2|Text=2.2K|Name=VALUE
|RECORD=2|OwnerIndex=1009|OwnerPartId=1|FormalType=1|Electrical=4|PinConglomerate=34|PinLength=10|Location.X=970|Location.Y=280|Name=1|Designator=1|PinPropagationDelay=0.000000E+000
|RECORD=2|OwnerIndex=1009|OwnerPartId=1|FormalType=1|Electrical=4|PinConglomerate=32|PinLength=10|Location.X=1000|Location.Y=280|Name=2|Designator=2|PinPropagationDelay=0.000000E+000
|RECORD=6|OwnerIndex=1009|IsNotAccesible=T|IndexInSheet=20|OwnerPartId=1|LineWidth=1|Color=16711680|LocationCount=7|X1=1000|Y1=280|X2=997|Y2=283|X3=991|Y3=277|X4=985|Y4=283|X5=979|Y5=277|X6=973|Y6=283|X7=970|Y7=280
|RECORD=41|OwnerIndex=1009|IndexInSheet=21|OwnerPartId=-1|Location.X=946|Location.X_Frac=61102|Location.Y=294|Color=8388608|FontID=1|IsHidden=T|Text=<VELENTIUM>|Name=VELENTIUM PART NUM
|RECORD=34|OwnerIndex=1009|IndexInSheet=-1|OwnerPartId=-1|Location.X=969|Location.Y=284|Color=8388608|FontID=3|Text=R9|Name=Designator|ReadOnlyState=1
|RECORD=41|OwnerIndex=1009|IndexInSheet=-1|OwnerPartId=-1|Location.X=980|Location.Y=270|Color=8388608|FontID=2|IsHidden=T|Text==MFG PART NUM|Name=Comment
|RECORD=44|OwnerIndex=1009
|RECORD=45|OwnerIndex=1036|IndexInSheet=-1|Description=Chip Resistor, 0603, 2-Leads, Body 1.57x0.85mm, IPC Medium Density|UseComponentLibrary=T|ModelName=RESC1608X50N|ModelType=PCBLIB|DatafileCount=1|ModelDatafileEntity0=RESC1608X50N|ModelDatafileKind0=PCBLib|IsCurrent=T|DatalinksLocked=T|DatabaseDatalinksLocked=T|IntegratedModel=T|DatabaseModel=T
|RECORD=46|OwnerIndex=1037
|RECORD=48|OwnerIndex=1037
|RECORD=1|LibReference=RES_0603_26.1K|ComponentDescription=RES, 26.1K, 1%, 1/10W, TF, 0603|PartCount=2|DisplayModeCount=1|IndexInSheet=74|OwnerPartId=-1|Location.X=1160|Location.Y=430|CurrentPartId=1|LibraryPath=*|SourceLibraryName=Resistors.IntLib|TargetFileName=*|AreaColor=11599871|Color=128|PartIDLocked=F|DesignItemId=RES_0603_26.1K|AllPinCount=2
|RECORD=41|OwnerIndex=1040|OwnerPartId=-1|Location.X=1160|Location.Y=430|Color=8388608|FontID=2|IsHidden=T|Text=7/25/2013|Name=ModifyDate
|RECORD=41|OwnerIndex=1040|IndexInSheet=1|OwnerPartId=-1|Location.X=1160|Location.Y=430|Color=8388608|FontID=2|IsHidden=T|Text=ERJ-3EKF2612V|Name=MFG PART NUM
|RECORD=41|OwnerIndex=1040|IndexInSheet=2|OwnerPartId=-1|Location.X=1160|Location.Y=430|Color=8388608|FontID=2|IsHidden=T|Text=PANASONIC|Name=MFG NAME
|RECORD=41|OwnerIndex=1040|IndexInSheet=3|OwnerPartId=-1|Location.X=1160|Location.Y=430|Color=8388608|FontID=2|IsHidden=T|Text=RES|Name=CATEGORY
|RECORD=41|OwnerIndex=1040|IndexInSheet=4|OwnerPartId=-1|Location.X=1158|Location.Y=440|Color=8388608|FontID=2|IsHidden=T|Text=7/26/2013|Name=Date
|RECORD=41|OwnerIndex=1040|IndexInSheet=5|OwnerPartId=-1|Location.X=1150|Location.X_Frac=55769|Location.Y=440|Color=8388608|FontID=2|IsHidden=T|Text=1%|Name=P1
|RECORD=41|OwnerIndex=1040|IndexInSheet=6|OwnerPartId=-1|Location.X=1150|Location.X_Frac=55769|Location.Y=440|Color=8388608|FontID=2|IsHidden=T|Text=TF|Name=P3
|RECORD=41|OwnerIndex=1040|IndexInSheet=7|OwnerPartId=-1|Location.X=1150|Location.X_Frac=55769|Location.Y=440|Color=8388608|FontID=2|IsHidden=T|Text=1/10W|Name=P2
|RECORD=41|OwnerIndex=1040|IndexInSheet=8|OwnerPartId=-1|Location.X=1150|Location.X_Frac=55769|Location.Y=440|Color=8388608|FontID=2|IsHidden=T|Text=125C|Name=MAXTEMP
|RECORD=41|OwnerIndex=1040|IndexInSheet=9|OwnerPartId=-1|Location.X=1150|Location.X_Frac=55769|Location.Y=440|Color=8388608|FontID=2|IsHidden=T|Text=-55C|Name=MINTEMP
|RECORD=41|OwnerIndex=1040|IndexInSheet=10|OwnerPartId=-1|Location.X=1150|Location.X_Frac=55769|Location.Y=440|Color=8388608|FontID=2|IsHidden=T|Text=100PPM|Name=OTHER
|RECORD=41|OwnerIndex=1040|IndexInSheet=11|OwnerPartId=-1|Location.X=1150|Location.X_Frac=55769|Location.Y=440|Color=8388608|FontID=2|IsHidden=T|Text=0603|Name=SIZE
|RECORD=41|OwnerIndex=1040|IndexInSheet=12|OwnerPartId=-1|Location.X=1150|Location.X_Frac=55769|Location.Y=440|Color=8388608|FontID=2|IsHidden=T|Text=GENERIC|Name=SUB
|RECORD=41|OwnerIndex=1040|IndexInSheet=13|OwnerPartId=-1|Location.X=1145|Location.X_Frac=98077|Location.Y=416|Color=8388608|FontID=1|IsHidden=T|Text=*|Name=SHEETPART
|RECORD=41|OwnerIndex=1040|IndexInSheet=14|OwnerPartId=-1|Location.X=1145|Location.X_Frac=98077|Location.Y=444|Color=8388608|FontID=1|IsHidden=T|Text=RES, 27.1K, 1%, 1/10W, TF, 0603|Name=DESC
|RECORD=41|OwnerIndex=1040|IndexInSheet=15|OwnerPartId=-1|Location.X=1146|Location.X_Frac=61102|Location.Y=444|Color=8388608|FontID=1|IsHidden=T|Text=<VELENTIUM>|Name=VELENTIUM PART NUM
|RECORD=41|OwnerIndex=1040|IndexInSheet=16|OwnerPartId=-1|Location.X=1145|Location.X_Frac=98077|Location.Y=444|Color=8388608|FontID=1|IsHidden=T|Text=Digi-Key|Name=Supplier 1|ReadOnlyState=3
|RECORD=41|OwnerIndex=1040|IndexInSheet=17|OwnerPartId=-1|Location.X=1145|Location.X_Frac=98077|Location.Y=444|Color=8388608|FontID=1|IsHidden=T|Text=P26.1KHCT-ND|Name=Supplier Part Number 1|ReadOnlyState=3
|RECORD=41|OwnerIndex=1040|IndexInSheet=18|OwnerPartId=-1|Location.X=1169|Location.Y=414|Color=8388608|FontID=2|Text=26.1K|Name=VALUE
|RECORD=2|OwnerIndex=1040|OwnerPartId=1|FormalType=1|Electrical=4|PinConglomerate=34|PinLength=10|Location.X=1170|Location.Y=430|Name=1|Designator=1|PinPropagationDelay=0.000000E+000
|RECORD=2|OwnerIndex=1040|OwnerPartId=1|FormalType=1|Electrical=4|PinConglomerate=32|PinLength=10|Location.X=1200|Location.Y=430|Name=2|Designator=2|PinPropagationDelay=0.000000E+000
|RECORD=6|OwnerIndex=1040|IsNotAccesible=T|IndexInSheet=21|OwnerPartId=1|LineWidth=1|Color=16711680|LocationCount=7|X1=1200|Y1=430|X2=1197|Y2=433|X3=1191|Y3=427|X4=1185|Y4=433|X5=1179|Y5=427|X6=1173|Y6=433|X7=1170|Y7=430
|RECORD=34|OwnerIndex=1040|IndexInSheet=-1|OwnerPartId=-1|Location.X=1169|Location.Y=434|Color=8388608|FontID=3|Text=R5|Name=Designator|ReadOnlyState=1
|RECORD=41|OwnerIndex=1040|IndexInSheet=-1|OwnerPartId=-1|Location.X=1180|Location.Y=420|Color=8388608|FontID=2|IsHidden=T|Text==MFG PART NUM|Name=Comment
|RECORD=44|OwnerIndex=1040
|RECORD=45|OwnerIndex=1067|IndexInSheet=-1|Description=Chip Resistor, 0603, 2-Leads, Body 1.57x0.85mm, IPC Medium Density|UseComponentLibrary=T|ModelName=RESC1608X50N|ModelType=PCBLIB|DatafileCount=1|ModelDatafileEntity0=RESC1608X50N|ModelDatafileKind0=PCBLib|IsCurrent=T|DatalinksLocked=T|DatabaseDatalinksLocked=T|IntegratedModel=T|DatabaseModel=T
|RECORD=46|OwnerIndex=1068
|RECORD=48|OwnerIndex=1068
|RECORD=1|LibReference=MP1482DS|ComponentDescription=IC, DC/DC, MP1482DS, >4.75VIN, 0.923-15V OUT, SOIC8|PartCount=2|DisplayModeCount=1|IndexInSheet=75|OwnerPartId=-1|Location.X=235|Location.Y=445|CurrentPartId=1|LibraryPath=*|SourceLibraryName=IntegratedCircuits.IntLib|TargetFileName=*|AreaColor=11599871|Color=128|PartIDLocked=F|DesignItemId=MP1482DS|AllPinCount=8
|RECORD=41|OwnerIndex=1071|OwnerPartId=-1|Location.X=235|Location.Y=445|Color=8388608|FontID=2|IsHidden=T|Text=MP1482DS-LF|Name=MFG PART NUM
|RECORD=41|OwnerIndex=1071|IndexInSheet=1|OwnerPartId=-1|Location.X=235|Location.Y=445|Color=8388608|FontID=2|IsHidden=T|Text=12/27/2005 8:34:25 AM|Name=MODIFY DATE
|RECORD=41|OwnerIndex=1071|IndexInSheet=2|OwnerPartId=-1|Location.X=235|Location.Y=445|Color=8388608|FontID=2|IsHidden=T|Text=MPS|Name=MFG NAME
|RECORD=41|OwnerIndex=1071|IndexInSheet=3|OwnerPartId=-1|Location.X=163|Location.Y=620|Color=8388608|FontID=2|IsHidden=T|Text=IC, DC/DC|Name=CATEGORY
|RECORD=41|OwnerIndex=1071|IndexInSheet=4|OwnerPartId=-1|Location.X=163|Location.Y=620|Color=8388608|FontID=2|IsHidden=T|Name=DATE
|RECORD=41|OwnerIndex=1071|IndexInSheet=5|OwnerPartId=-1|Location.X=163|Location.Y=620|Color=8388608|FontID=2|IsHidden=T|Text=+85C|Name=MAXTEMP
|RECORD=41|OwnerIndex=1071|IndexInSheet=6|OwnerPartId=-1|Location.X=163|Location.Y=620|Color=8388608|FontID=2|IsHidden=T|Text=-40C|Name=MINTEMP
|RECORD=41|OwnerIndex=1071|IndexInSheet=7|OwnerPartId=-1|Location.X=163|Location.Y=620|Color=8388608|FontID=2|IsHidden=T|Text=additional spec|Name=OTHER
|RECORD=41|OwnerIndex=1071|IndexInSheet=8|OwnerPartId=-1|Location.X=163|Location.Y=620|Color=8388608|FontID=2|IsHidden=T|Text=>4.75V IN|Name=P1
|RECORD=41|OwnerIndex=1071|IndexInSheet=9|OwnerPartId=-1|Location.X=163|Location.Y=620|Color=8388608|FontID=2|IsHidden=T|Text=0.923-15V OUT|Name=P2
|RECORD=41|OwnerIndex=1071|IndexInSheet=10|OwnerPartId=-1|Location.X=163|Location.Y=620|Color=8388608|FontID=2|IsHidden=T|Text=W|Name=P3
|RECORD=41|OwnerIndex=1071|IndexInSheet=11|OwnerPartId=-1|Location.X=163|Location.Y=620|Color=8388608|FontID=2|IsHidden=T|Text=8SOIC|Name=SIZE
|RECORD=41|OwnerIndex=1071|IndexInSheet=12|OwnerPartId=-1|Location.X=163|Location.Y=620|Color=8388608|FontID=2|IsHidden=T|Name=SUB
|RECORD=41|OwnerIndex=1071|IndexInSheet=13|OwnerPartId=-1|Location.X=163|Location.Y=433|Color=8388608|FontID=1|IsHidden=T|Text=*|Name=SHEETPART
|RECORD=41|OwnerIndex=1071|IndexInSheet=14|OwnerPartId=-1|Location.X=163|Location.Y=596|Color=8388608|FontID=1|IsHidden=T|Text=IC, DC/DC, MP1482DS, >4.75VIN, 0.923-15V OUT, SOIC8|Name=DESC
|RECORD=41|OwnerIndex=1071|IndexInSheet=15|OwnerPartId=-1|Location.X=163|Location.Y=596|Color=8388608|FontID=1|IsHidden=T|Text=<V PART NUM>|Name=VELENTIUM PART NUM
|RECORD=41|OwnerIndex=1071|IndexInSheet=16|OwnerPartId=-1|Location.X=148|Location.Y=522|Color=8388608|FontID=1|IsHidden=T|Text=Digi-Key|Name=Supplier 1|ReadOnlyState=3
|RECORD=41|OwnerIndex=1071|IndexInSheet=17|OwnerPartId=-1|Location.X=148|Location.Y=522|Color=8388608|FontID=1|IsHidden=T|Text=1589-1524-1-ND|Name=Supplier Part Number 1|ReadOnlyState=3
|RECORD=41|OwnerIndex=1071|IndexInSheet=18|OwnerPartId=-1|Location.X=310|Location.Y=480|Color=8388608|FontID=2|Text=MP1482DS|Name=VALUE
|RECORD=14|OwnerIndex=1071|IsNotAccesible=T|IndexInSheet=19|OwnerPartId=1|Location.X=180|Location.Y=400|Corner.X=290|Corner.Y=490|LineWidth=1|Color=128|AreaColor=11599871|IsSolid=T|Transparent=T
|RECORD=2|OwnerIndex=1071|OwnerPartId=1|FormalType=1|Electrical=4|PinConglomerate=57|PinLength=30|Location.X=260|Location.Y=490|Name=BS|Designator=1|SwapIDPart=Ž&Ž||PinPropagationDelay=0.000000E+000
|RECORD=2|OwnerIndex=1071|OwnerPartId=1|FormalType=1|Electrical=4|PinConglomerate=57|PinLength=30|Location.X=210|Location.Y=490|Name=IN|Designator=2|SwapIDPart=Ž&Ž||PinPropagationDelay=0.000000E+000
|RECORD=2|OwnerIndex=1071|OwnerPartId=1|FormalType=1|Electrical=4|PinConglomerate=56|PinLength=30|Location.X=290|Location.Y=460|Name=SW|Designator=3|SwapIDPart=Ž&Ž||PinPropagationDelay=0.000000E+000
|RECORD=2|OwnerIndex=1071|OwnerPartId=1|FormalType=1|Electrical=4|PinConglomerate=56|PinLength=30|Location.X=290|Location.Y=430|Name=FB|Designator=5|SwapIDPart=Ž&Ž||PinPropagationDelay=0.000000E+000
|RECORD=2|OwnerIndex=1071|OwnerPartId=1|FormalType=1|Electrical=4|PinConglomerate=58|PinLength=30|Location.X=180|Location.Y=460|Name=EN|Designator=7|SwapIDPart=Ž&Ž||PinPropagationDelay=0.000000E+000
|RECORD=2|OwnerIndex=1071|OwnerPartId=1|FormalType=1|Electrical=4|PinConglomerate=58|PinLength=30|Location.X=180|Location.Y=430|Name=SS|Designator=8|SwapIDPart=Ž&Ž||PinPropagationDelay=0.000000E+000
|RECORD=2|OwnerIndex=1071|OwnerPartId=1|FormalType=1|Electrical=4|PinConglomerate=59|PinLength=30|Location.X=210|Location.Y=400|Name=GND|Designator=4|SwapIDPart=Ž&Ž||PinPropagationDelay=0.000000E+000
|RECORD=2|OwnerIndex=1071|OwnerPartId=1|FormalType=1|Electrical=4|PinConglomerate=59|PinLength=30|Location.X=260|Location.Y=400|Name=COMP|Designator=6|SwapIDPart=Ž&Ž||PinPropagationDelay=0.000000E+000
|RECORD=34|OwnerIndex=1071|IndexInSheet=-1|OwnerPartId=-1|Location.X=310|Location.Y=490|Color=8388608|FontID=3|Text=U1|Name=Designator|ReadOnlyState=1
|RECORD=41|OwnerIndex=1071|IndexInSheet=-1|OwnerPartId=-1|Location.X=195|Location.Y=605|Color=8388608|FontID=2|IsHidden=T|Text=MP1482DS-LF|Name=Comment
|RECORD=44|OwnerIndex=1071
|RECORD=45|OwnerIndex=1110|IndexInSheet=-1|Description=SOIC127P600X175-8N|UseComponentLibrary=T|ModelName=SOIC127P600X175-8N|ModelType=PCBLIB|DatafileCount=1|ModelDatafileEntity0=SOIC127P600X175-8N|ModelDatafileKind0=PCBLib|IsCurrent=T|DatalinksLocked=T|DatabaseDatalinksLocked=T|IntegratedModel=T|DatabaseModel=T
|RECORD=46|OwnerIndex=1111
|RECORD=48|OwnerIndex=1111
|RECORD=1|LibReference=MP1482DS|ComponentDescription=IC, DC/DC, MP1482DS, >4.75VIN, 0.923-15V OUT, SOIC8|PartCount=2|DisplayModeCount=1|IndexInSheet=76|OwnerPartId=-1|Location.X=985|Location.Y=445|CurrentPartId=1|LibraryPath=*|SourceLibraryName=IntegratedCircuits.IntLib|TargetFileName=*|AreaColor=11599871|Color=128|PartIDLocked=F|DesignItemId=MP1482DS|AllPinCount=8
|RECORD=41|OwnerIndex=1114|OwnerPartId=-1|Location.X=985|Location.Y=445|Color=8388608|FontID=2|IsHidden=T|Text=MP1482DS-LF|Name=MFG PART NUM
|RECORD=41|OwnerIndex=1114|IndexInSheet=1|OwnerPartId=-1|Location.X=985|Location.Y=445|Color=8388608|FontID=2|IsHidden=T|Text=12/27/2005 8:34:25 AM|Name=MODIFY DATE
|RECORD=41|OwnerIndex=1114|IndexInSheet=2|OwnerPartId=-1|Location.X=985|Location.Y=445|Color=8388608|FontID=2|IsHidden=T|Text=MPS|Name=MFG NAME
|RECORD=41|OwnerIndex=1114|IndexInSheet=3|OwnerPartId=-1|Location.X=913|Location.Y=620|Color=8388608|FontID=2|IsHidden=T|Text=IC, DC/DC|Name=CATEGORY
|RECORD=41|OwnerIndex=1114|IndexInSheet=4|OwnerPartId=-1|Location.X=913|Location.Y=620|Color=8388608|FontID=2|IsHidden=T|Name=DATE
|RECORD=41|OwnerIndex=1114|IndexInSheet=5|OwnerPartId=-1|Location.X=913|Location.Y=620|Color=8388608|FontID=2|IsHidden=T|Text=+85C|Name=MAXTEMP
|RECORD=41|OwnerIndex=1114|IndexInSheet=6|OwnerPartId=-1|Location.X=913|Location.Y=620|Color=8388608|FontID=2|IsHidden=T|Text=-40C|Name=MINTEMP
|RECORD=41|OwnerIndex=1114|IndexInSheet=7|OwnerPartId=-1|Location.X=913|Location.Y=620|Color=8388608|FontID=2|IsHidden=T|Text=additional spec|Name=OTHER
|RECORD=41|OwnerIndex=1114|IndexInSheet=8|OwnerPartId=-1|Location.X=913|Location.Y=620|Color=8388608|FontID=2|IsHidden=T|Text=>4.75V IN|Name=P1
|RECORD=41|OwnerIndex=1114|IndexInSheet=9|OwnerPartId=-1|Location.X=913|Location.Y=620|Color=8388608|FontID=2|IsHidden=T|Text=0.923-15V OUT|Name=P2
|RECORD=41|OwnerIndex=1114|IndexInSheet=10|OwnerPartId=-1|Location.X=913|Location.Y=620|Color=8388608|FontID=2|IsHidden=T|Text=W|Name=P3
|RECORD=41|OwnerIndex=1114|IndexInSheet=11|OwnerPartId=-1|Location.X=913|Location.Y=620|Color=8388608|FontID=2|IsHidden=T|Text=8SOIC|Name=SIZE
|RECORD=41|OwnerIndex=1114|IndexInSheet=12|OwnerPartId=-1|Location.X=913|Location.Y=620|Color=8388608|FontID=2|IsHidden=T|Name=SUB
|RECORD=41|OwnerIndex=1114|IndexInSheet=13|OwnerPartId=-1|Location.X=913|Location.Y=433|Color=8388608|FontID=1|IsHidden=T|Text=*|Name=SHEETPART
|RECORD=41|OwnerIndex=1114|IndexInSheet=14|OwnerPartId=-1|Location.X=913|Location.Y=596|Color=8388608|FontID=1|IsHidden=T|Text=IC, DC/DC, MP1482DS, >4.75VIN, 0.923-15V OUT, SOIC8|Name=DESC
|RECORD=41|OwnerIndex=1114|IndexInSheet=15|OwnerPartId=-1|Location.X=913|Location.Y=596|Color=8388608|FontID=1|IsHidden=T|Text=<V PART NUM>|Name=VELENTIUM PART NUM
|RECORD=41|OwnerIndex=1114|IndexInSheet=16|OwnerPartId=-1|Location.X=898|Location.Y=522|Color=8388608|FontID=1|IsHidden=T|Text=Digi-Key|Name=Supplier 1|ReadOnlyState=3
|RECORD=41|OwnerIndex=1114|IndexInSheet=17|OwnerPartId=-1|Location.X=898|Location.Y=522|Color=8388608|FontID=1|IsHidden=T|Text=1589-1524-1-ND|Name=Supplier Part Number 1|ReadOnlyState=3
|RECORD=41|OwnerIndex=1114|IndexInSheet=18|OwnerPartId=-1|Location.X=1040|Location.Y=480|Color=8388608|FontID=2|Text=MP1482DS|Name=VALUE
|RECORD=14|OwnerIndex=1114|IsNotAccesible=T|IndexInSheet=19|OwnerPartId=1|Location.X=930|Location.Y=400|Corner.X=1040|Corner.Y=490|LineWidth=1|Color=128|AreaColor=11599871|IsSolid=T|Transparent=T
|RECORD=2|OwnerIndex=1114|OwnerPartId=1|FormalType=1|Electrical=4|PinConglomerate=57|PinLength=30|Location.X=1010|Location.Y=490|Name=BS|Designator=1|SwapIDPart=Ž&Ž||PinPropagationDelay=0.000000E+000
|RECORD=2|OwnerIndex=1114|OwnerPartId=1|FormalType=1|Electrical=4|PinConglomerate=57|PinLength=30|Location.X=960|Location.Y=490|Name=IN|Designator=2|SwapIDPart=Ž&Ž||PinPropagationDelay=0.000000E+000
|RECORD=2|OwnerIndex=1114|OwnerPartId=1|FormalType=1|Electrical=4|PinConglomerate=56|PinLength=30|Location.X=1040|Location.Y=460|Name=SW|Designator=3|SwapIDPart=Ž&Ž||PinPropagationDelay=0.000000E+000
|RECORD=2|OwnerIndex=1114|OwnerPartId=1|FormalType=1|Electrical=4|PinConglomerate=56|PinLength=30|Location.X=1040|Location.Y=430|Name=FB|Designator=5|SwapIDPart=Ž&Ž||PinPropagationDelay=0.000000E+000
|RECORD=2|OwnerIndex=1114|OwnerPartId=1|FormalType=1|Electrical=4|PinConglomerate=58|PinLength=30|Location.X=930|Location.Y=460|Name=EN|Designator=7|SwapIDPart=Ž&Ž||PinPropagationDelay=0.000000E+000
|RECORD=2|OwnerIndex=1114|OwnerPartId=1|FormalType=1|Electrical=4|PinConglomerate=58|PinLength=30|Location.X=930|Location.Y=430|Name=SS|Designator=8|SwapIDPart=Ž&Ž||PinPropagationDelay=0.000000E+000
|RECORD=2|OwnerIndex=1114|OwnerPartId=1|FormalType=1|Electrical=4|PinConglomerate=59|PinLength=30|Location.X=960|Location.Y=400|Name=GND|Designator=4|SwapIDPart=Ž&Ž||PinPropagationDelay=0.000000E+000
|RECORD=2|OwnerIndex=1114|OwnerPartId=1|FormalType=1|Electrical=4|PinConglomerate=59|PinLength=30|Location.X=1010|Location.Y=400|Name=COMP|Designator=6|SwapIDPart=Ž&Ž||PinPropagationDelay=0.000000E+000
|RECORD=34|OwnerIndex=1114|IndexInSheet=-1|OwnerPartId=-1|Location.X=1040|Location.Y=490|Color=8388608|FontID=3|Text=U2|Name=Designator|ReadOnlyState=1
|RECORD=41|OwnerIndex=1114|IndexInSheet=-1|OwnerPartId=-1|Location.X=945|Location.Y=605|Color=8388608|FontID=2|IsHidden=T|Text=MP1482DS-LF|Name=Comment
|RECORD=44|OwnerIndex=1114
|RECORD=45|OwnerIndex=1153|IndexInSheet=-1|Description=SOIC127P600X175-8N|UseComponentLibrary=T|ModelName=SOIC127P600X175-8N|ModelType=PCBLIB|DatafileCount=1|ModelDatafileEntity0=SOIC127P600X175-8N|ModelDatafileKind0=PCBLib|IsCurrent=T|DatalinksLocked=T|DatabaseDatalinksLocked=T|IntegratedModel=T|DatabaseModel=T
|RECORD=46|OwnerIndex=1154
|RECORD=48|OwnerIndex=1154
|RECORD=17|IndexInSheet=77|OwnerPartId=-1|ShowNetName=T|Location.X=120|Location.Y=680|Orientation=1|Color=128|FontID=1|Text=+12V_PCIE
|RECORD=1|LibReference=FUSE_0603_2.00A|ComponentDescription=FUSE SLOW 2.00A 32V M 0603|PartCount=2|DisplayModeCount=1|IndexInSheet=78|OwnerPartId=-1|Location.X=530|Location.Y=970|CurrentPartId=1|LibraryPath=*|SourceLibraryName=Passives.IntLib|TargetFileName=*|AreaColor=11599871|Color=128|PartIDLocked=F|DesignItemId=FUSE_0603_2.00A|AllPinCount=2
|RECORD=41|OwnerIndex=1158|OwnerPartId=-1|Location.X=530|Location.Y=970|Color=8388608|FontID=2|IsHidden=T|Text=SF-0603S200-2|Name=MFG PART NUM
|RECORD=41|OwnerIndex=1158|IndexInSheet=1|OwnerPartId=-1|Location.X=530|Location.Y=970|Color=8388608|FontID=2|IsHidden=T|Text=9/4/2013|Name=MODIFY DATE
|RECORD=41|OwnerIndex=1158|IndexInSheet=2|OwnerPartId=-1|Location.X=530|Location.Y=970|Color=8388608|FontID=2|IsHidden=T|Text=BOURNS|Name=MFG NAME
|RECORD=41|OwnerIndex=1158|IndexInSheet=3|OwnerPartId=-1|Location.X=530|Location.Y=970|Color=8388608|FontID=2|IsHidden=T|Text=FUSE|Name=CATEGORY
|RECORD=41|OwnerIndex=1158|IndexInSheet=4|OwnerPartId=-1|Location.X=528|Location.Y=987|Color=8388608|FontID=2|IsHidden=T|Text=20 OCT 15|Name=DATE
|RECORD=41|OwnerIndex=1158|IndexInSheet=5|OwnerPartId=-1|Location.X=528|Location.Y=987|Color=8388608|FontID=2|IsHidden=T|Text=105C|Name=MAXTEMP
|RECORD=41|OwnerIndex=1158|IndexInSheet=6|OwnerPartId=-1|Location.X=528|Location.Y=987|Color=8388608|FontID=2|IsHidden=T|Text=-40C|Name=MINTEMP
|RECORD=41|OwnerIndex=1158|IndexInSheet=7|OwnerPartId=-1|Location.X=528|Location.Y=987|Color=8388608|FontID=2|IsHidden=T|Text=UL E141069|Name=OTHER
|RECORD=41|OwnerIndex=1158|IndexInSheet=8|OwnerPartId=-1|Location.X=528|Location.Y=987|Color=8388608|FontID=2|IsHidden=T|Text=SLOW BLO|Name=P1
|RECORD=41|OwnerIndex=1158|IndexInSheet=9|OwnerPartId=-1|Location.X=528|Location.Y=987|Color=8388608|FontID=2|IsHidden=T|Text=32V|Name=P2
|RECORD=41|OwnerIndex=1158|IndexInSheet=10|OwnerPartId=-1|Location.X=528|Location.Y=987|Color=8388608|FontID=2|IsHidden=T|Text=M|Name=P3
|RECORD=41|OwnerIndex=1158|IndexInSheet=11|OwnerPartId=-1|Location.X=528|Location.Y=987|Color=8388608|FontID=2|IsHidden=T|Text=0603|Name=SIZE
|RECORD=41|OwnerIndex=1158|IndexInSheet=12|OwnerPartId=-1|Location.X=528|Location.Y=987|Color=8388608|FontID=2|IsHidden=T|Name=SUB
|RECORD=41|OwnerIndex=1158|IndexInSheet=13|OwnerPartId=-1|Location.X=528|Location.Y=943|Color=8388608|FontID=1|IsHidden=T|Text=*|Name=SHEETPART
|RECORD=41|OwnerIndex=1158|IndexInSheet=14|OwnerPartId=-1|Location.X=528|Location.Y=991|Color=8388608|FontID=1|IsHidden=T|Text=FUSE SLOW 1.25A 32V M 0603|Name=DESC
|RECORD=41|OwnerIndex=1158|IndexInSheet=15|OwnerPartId=-1|Location.X=528|Location.Y=991|Color=8388608|FontID=1|IsHidden=T|Text=<VALENTIUM>|Name=VALENTIUM PART NUM
|RECORD=41|OwnerIndex=1158|IndexInSheet=16|OwnerPartId=-1|Location.X=528|Location.Y=991|Color=8388608|FontID=1|IsHidden=T|Text=Digi-Key|Name=Supplier 1|ReadOnlyState=3
|RECORD=2|OwnerIndex=1158|OwnerPartId=1|FormalType=1|Electrical=4|PinConglomerate=34|PinLength=20|Location.X=550|Location.Y=970|Name=1|Designator=1|SwapIdPin=1|SwapIDPart=1|PinPropagationDelay=0.000000E+000
|RECORD=2|OwnerIndex=1158|OwnerPartId=1|FormalType=1|Electrical=4|PinConglomerate=32|PinLength=20|Location.X=570|Location.Y=970|Name=2|Designator=2|SwapIdPin=2|SwapIDPart=1|PinPropagationDelay=0.000000E+000
|RECORD=12|OwnerIndex=1158|IsNotAccesible=T|IndexInSheet=19|OwnerPartId=1|Location.X=565|Location.Y=970|Radius=5|LineWidth=1|StartAngle=180.000|Color=16711680
|RECORD=12|OwnerIndex=1158|IsNotAccesible=T|IndexInSheet=20|OwnerPartId=1|Location.X=555|Location.Y=970|Radius=5|LineWidth=1|EndAngle=180.000|Color=16711680
|RECORD=41|OwnerIndex=1158|IndexInSheet=21|OwnerPartId=-1|Location.X=548|Location.Y=953|Color=8388608|FontID=2|Text=2.00A|Name=VALUE
|RECORD=8|OwnerIndex=1158|IsNotAccesible=T|IndexInSheet=22|OwnerPartId=1|Location.X=550|Location.Y=970|Radius=2|SecondaryRadius=2|LineWidth=1|Color=16711680|AreaColor=16777215|IsSolid=T
|RECORD=8|OwnerIndex=1158|IsNotAccesible=T|IndexInSheet=23|OwnerPartId=1|Location.X=570|Location.Y=970|Radius=2|SecondaryRadius=2|LineWidth=1|Color=16711680|AreaColor=16777215|IsSolid=T
|RECORD=41|OwnerIndex=1158|IndexInSheet=24|OwnerPartId=-1|Location.X=548|Location.Y=943|Color=8388608|FontID=1|IsHidden=T|Text=SF-0603S200-2CT-ND|Name=Supplier Part Number 1|ReadOnlyState=3
|RECORD=34|OwnerIndex=1158|IndexInSheet=-1|OwnerPartId=-1|Location.X=548|Location.Y=975|Color=8388608|FontID=3|Text=F1|Name=Designator|ReadOnlyState=1
|RECORD=41|OwnerIndex=1158|IndexInSheet=-1|OwnerPartId=-1|Location.X=570|Location.Y=947|Location.Y_Frac=10000|Color=8388608|FontID=2|IsHidden=T|Text=FUSE_0603_2.00A|Name=Comment
|RECORD=44|OwnerIndex=1158
|RECORD=45|OwnerIndex=1188|IndexInSheet=-1|Description=Chip Fuse, 0603, 2-Leads, Body 1.60x0.81mm, IPC Medium Density|UseComponentLibrary=T|ModelName=FUSM1608X60N|ModelType=PCBLIB|DatafileCount=1|ModelDatafileEntity0=FUSM1608X60N|ModelDatafileKind0=PCBLib|IsCurrent=T|DatalinksLocked=T|DatabaseDatalinksLocked=T|IntegratedModel=T|DatabaseModel=T
|RECORD=46|OwnerIndex=1189
|RECORD=48|OwnerIndex=1189
|RECORD=27|IndexInSheet=79|OwnerPartId=-1|LineWidth=1|Color=8388608|LocationCount=2|X1=210|Y1=800|X2=160|Y2=800
|RECORD=27|IndexInSheet=80|OwnerPartId=-1|LineWidth=1|Color=8388608|LocationCount=4|X1=100|Y1=360|X2=100|Y2=320|X3=50|Y3=320|X4=50|Y4=500
|RECORD=27|IndexInSheet=81|OwnerPartId=-1|LineWidth=1|Color=8388608|LocationCount=5|X1=210|Y1=520|X2=210|Y2=550|X3=110|Y3=550|X4=50|Y4=550|X5=50|Y5=530
|RECORD=27|IndexInSheet=82|OwnerPartId=-1|LineWidth=1|Color=8388608|LocationCount=3|X1=210|Y1=370|X2=210|Y2=320|X3=100|Y3=320
|RECORD=27|IndexInSheet=83|OwnerPartId=-1|LineWidth=1|Color=8388608|LocationCount=3|X1=150|Y1=430|X2=100|Y2=430|X3=100|Y3=390
|RECORD=27|IndexInSheet=84|OwnerPartId=-1|LineWidth=1|Color=8388608|LocationCount=3|X1=110|Y1=490|X2=110|Y2=460|X3=150|Y3=460
|RECORD=27|IndexInSheet=85|OwnerPartId=-1|LineWidth=1|Color=8388608|LocationCount=3|X1=180|Y1=670|X2=120|Y2=670|X3=120|Y3=680
|RECORD=27|IndexInSheet=86|OwnerPartId=-1|LineWidth=1|Color=8388608|LocationCount=2|X1=160|Y1=790|X2=210|Y2=790
|RECORD=27|IndexInSheet=87|OwnerPartId=-1|LineWidth=1|Color=8388608|LocationCount=5|X1=160|Y1=810|X2=210|Y2=810|X3=210|Y3=800|X4=210|Y4=790|X5=210|Y5=760
|RECORD=27|IndexInSheet=88|OwnerPartId=-1|LineWidth=1|Color=8388608|LocationCount=4|X1=160|Y1=820|X2=210|Y2=820|X3=210|Y3=830|X4=210|Y4=840
|RECORD=27|IndexInSheet=89|OwnerPartId=-1|LineWidth=1|Color=8388608|LocationCount=2|X1=210|Y1=830|X2=160|Y2=830
|RECORD=27|IndexInSheet=90|OwnerPartId=-1|LineWidth=1|Color=8388608|LocationCount=3|X1=160|Y1=840|X2=210|Y2=840|X3=260|Y3=840
|RECORD=27|IndexInSheet=91|OwnerPartId=-1|LineWidth=1|Color=8388608|LocationCount=2|X1=190|Y1=930|X2=210|Y2=930
|RECORD=27|IndexInSheet=92|OwnerPartId=-1|LineWidth=1|Color=8388608|LocationCount=4|X1=190|Y1=940|X2=210|Y2=940|X3=210|Y3=930|X4=210|Y4=900
|RECORD=27|IndexInSheet=93|OwnerPartId=-1|LineWidth=1|Color=8388608|LocationCount=2|X1=190|Y1=950|X2=260|Y2=950
|RECORD=27|IndexInSheet=94|OwnerPartId=-1|LineWidth=1|Color=8388608|LocationCount=3|X1=240|Y1=670|X2=490|Y2=670|X3=490|Y3=840
|RECORD=27|IndexInSheet=95|OwnerPartId=-1|LineWidth=1|Color=8388608|LocationCount=3|X1=260|Y1=520|X2=260|Y2=550|X3=320|Y3=550
|RECORD=27|IndexInSheet=96|OwnerPartId=-1|LineWidth=1|Color=8388608|LocationCount=3|X1=320|Y1=430|X2=380|Y2=430|X3=390|Y3=430
|RECORD=27|IndexInSheet=97|OwnerPartId=-1|LineWidth=1|Color=8388608|LocationCount=4|X1=350|Y1=550|X2=370|Y2=550|X3=370|Y3=460|X4=320|Y4=460
|RECORD=27|IndexInSheet=98|OwnerPartId=-1|LineWidth=1|Color=8388608|LocationCount=3|X1=320|Y1=840|X2=490|Y2=840|X3=490|Y3=950
|RECORD=27|IndexInSheet=99|OwnerPartId=-1|LineWidth=1|Color=8388608|LocationCount=2|X1=320|Y1=950|X2=350|Y2=950
|RECORD=27|IndexInSheet=100|OwnerPartId=-1|LineWidth=1|Color=8388608|LocationCount=7|X1=380|Y1=350|X2=380|Y2=320|X3=500|Y3=320|X4=550|Y4=320|X5=600|Y5=320|X6=650|Y6=320|X7=700|Y7=320
|RECORD=27|IndexInSheet=101|OwnerPartId=-1|LineWidth=1|Color=8388608|LocationCount=4|X1=410|Y1=950|X2=490|Y2=950|X3=490|Y3=970|X4=530|Y4=970
|RECORD=27|IndexInSheet=102|OwnerPartId=-1|LineWidth=1|Color=8388608|LocationCount=7|X1=440|Y1=430|X2=450|Y2=430|X3=500|Y3=430|X4=550|Y4=430|X5=600|Y5=430|X6=650|Y6=430|X7=700|Y7=430
|RECORD=27|IndexInSheet=103|OwnerPartId=-1|LineWidth=1|Color=8388608|LocationCount=4|X1=590|Y1=970|X2=630|Y2=970|X3=680|Y3=970|X4=680|Y4=930
|RECORD=27|IndexInSheet=104|OwnerPartId=-1|LineWidth=1|Color=8388608|LocationCount=4|X1=630|Y1=900|X2=630|Y2=890|X3=680|Y3=890|X4=680|Y4=880
|RECORD=27|IndexInSheet=105|OwnerPartId=-1|LineWidth=1|Color=8388608|LocationCount=3|X1=700|Y1=320|X2=750|Y2=320|X3=750|Y3=370
|RECORD=27|IndexInSheet=106|OwnerPartId=-1|LineWidth=1|Color=8388608|LocationCount=3|X1=700|Y1=430|X2=750|Y2=430|X3=750|Y3=400
|RECORD=27|IndexInSheet=107|OwnerPartId=-1|LineWidth=1|Color=8388608|LocationCount=5|X1=960|Y1=370|X2=960|Y2=280|X3=880|Y3=280|X4=820|Y4=280|X5=820|Y5=510
|RECORD=27|IndexInSheet=108|OwnerPartId=-1|LineWidth=1|Color=8388608|LocationCount=5|X1=960|Y1=520|X2=960|Y2=560|X3=880|Y3=560|X4=820|Y4=560|X5=820|Y5=540
|RECORD=27|IndexInSheet=109|OwnerPartId=-1|LineWidth=1|Color=8388608|LocationCount=3|X1=900|Y1=430|X2=880|Y2=430|X3=880|Y3=360
|RECORD=27|IndexInSheet=110|OwnerPartId=-1|LineWidth=1|Color=8388608|LocationCount=3|X1=900|Y1=460|X2=880|Y2=460|X3=880|Y3=490
|RECORD=27|IndexInSheet=111|OwnerPartId=-1|LineWidth=1|Color=8388608|LocationCount=3|X1=1010|Y1=520|X2=1010|Y2=560|X3=1040|Y3=560
|RECORD=27|IndexInSheet=112|OwnerPartId=-1|LineWidth=1|Color=8388608|LocationCount=2|X1=1100|Y1=430|X2=1070|Y2=430
|RECORD=27|IndexInSheet=113|OwnerPartId=-1|LineWidth=1|Color=8388608|LocationCount=4|X1=1070|Y1=560|X2=1100|Y2=560|X3=1100|Y3=460|X4=1070|Y4=460
|RECORD=27|IndexInSheet=114|OwnerPartId=-1|LineWidth=1|Color=8388608|LocationCount=7|X1=1410|Y1=380|X2=1410|Y2=280|X3=1360|Y3=280|X4=1310|Y4=280|X5=1260|Y5=280|X6=1100|Y6=280|X7=1100|Y7=310
|RECORD=27|IndexInSheet=115|OwnerPartId=-1|LineWidth=1|Color=8388608|LocationCount=3|X1=1160|Y1=430|X2=1100|Y2=430|X3=1100|Y3=360
|RECORD=27|IndexInSheet=116|OwnerPartId=-1|LineWidth=1|Color=8388608|LocationCount=2|X1=1100|Y1=460|X2=1140|Y2=460
|RECORD=27|IndexInSheet=117|OwnerPartId=-1|LineWidth=1|Color=8388608|LocationCount=2|X1=1210|Y1=430|X2=1260|Y2=430
|RECORD=27|IndexInSheet=118|OwnerPartId=-1|LineWidth=1|Color=8388608|LocationCount=3|X1=1220|Y1=460|X2=1260|Y2=460|X3=1260|Y3=430
|RECORD=27|IndexInSheet=119|OwnerPartId=-1|LineWidth=1|Color=8388608|LocationCount=5|X1=1260|Y1=430|X2=1310|Y2=430|X3=1360|Y3=430|X4=1410|Y4=430|X5=1410|Y5=410
|RECORD=27|IndexInSheet=120|OwnerPartId=-1|LineWidth=1|Color=8388608|LocationCount=4|X1=1510|Y1=380|X2=1510|Y2=280|X3=1460|Y3=280|X4=1410|Y4=280
|RECORD=27|IndexInSheet=121|OwnerPartId=-1|LineWidth=1|Color=8388608|LocationCount=4|X1=1410|Y1=430|X2=1460|Y2=430|X3=1510|Y3=430|X4=1510|Y4=410
|RECORD=27|IndexInSheet=122|OwnerPartId=-1|LineWidth=1|Color=8388608|LocationCount=2|X1=110|Y1=540|X2=110|Y2=550
|RECORD=27|IndexInSheet=123|OwnerPartId=-1|LineWidth=1|Color=8388608|LocationCount=2|X1=260|Y1=320|X2=260|Y2=330
|RECORD=27|IndexInSheet=124|OwnerPartId=-1|LineWidth=1|Color=8388608|LocationCount=2|X1=260|Y1=360|X2=260|Y2=370
|RECORD=27|IndexInSheet=125|OwnerPartId=-1|LineWidth=1|Color=8388608|LocationCount=2|X1=380|Y1=430|X2=380|Y2=400
|RECORD=27|IndexInSheet=126|OwnerPartId=-1|LineWidth=1|Color=8388608|LocationCount=2|X1=450|Y1=460|X2=450|Y2=430
|RECORD=27|IndexInSheet=127|OwnerPartId=-1|LineWidth=1|Color=8388608|LocationCount=2|X1=450|Y1=540|X2=450|Y2=460
|RECORD=27|IndexInSheet=128|OwnerPartId=-1|LineWidth=1|Color=8388608|LocationCount=2|X1=500|Y1=370|X2=500|Y2=320
|RECORD=27|IndexInSheet=129|OwnerPartId=-1|LineWidth=1|Color=8388608|LocationCount=2|X1=500|Y1=400|X2=500|Y2=430
|RECORD=27|IndexInSheet=130|OwnerPartId=-1|LineWidth=1|Color=8388608|LocationCount=2|X1=550|Y1=370|X2=550|Y2=320
|RECORD=27|IndexInSheet=131|OwnerPartId=-1|LineWidth=1|Color=8388608|LocationCount=2|X1=550|Y1=400|X2=550|Y2=430
|RECORD=27|IndexInSheet=132|OwnerPartId=-1|LineWidth=1|Color=8388608|LocationCount=2|X1=600|Y1=370|X2=600|Y2=320
|RECORD=27|IndexInSheet=133|OwnerPartId=-1|LineWidth=1|Color=8388608|LocationCount=2|X1=600|Y1=430|X2=600|Y2=400
|RECORD=27|IndexInSheet=134|OwnerPartId=-1|LineWidth=1|Color=8388608|LocationCount=2|X1=630|Y1=930|X2=630|Y2=970
|RECORD=27|IndexInSheet=135|OwnerPartId=-1|LineWidth=1|Color=8388608|LocationCount=2|X1=650|Y1=370|X2=650|Y2=320
|RECORD=27|IndexInSheet=136|OwnerPartId=-1|LineWidth=1|Color=8388608|LocationCount=2|X1=650|Y1=400|X2=650|Y2=430
|RECORD=27|IndexInSheet=137|OwnerPartId=-1|LineWidth=1|Color=8388608|LocationCount=2|X1=680|Y1=900|X2=680|Y2=890
|RECORD=27|IndexInSheet=138|OwnerPartId=-1|LineWidth=1|Color=8388608|LocationCount=2|X1=680|Y1=970|X2=680|Y2=990
|RECORD=27|IndexInSheet=139|OwnerPartId=-1|LineWidth=1|Color=8388608|LocationCount=2|X1=700|Y1=370|X2=700|Y2=320
|RECORD=27|IndexInSheet=140|OwnerPartId=-1|LineWidth=1|Color=8388608|LocationCount=2|X1=700|Y1=400|X2=700|Y2=430
|RECORD=27|IndexInSheet=141|OwnerPartId=-1|LineWidth=1|Color=8388608|LocationCount=2|X1=880|Y1=330|X2=880|Y2=280
|RECORD=27|IndexInSheet=142|OwnerPartId=-1|LineWidth=1|Color=8388608|LocationCount=2|X1=880|Y1=540|X2=880|Y2=560
|RECORD=27|IndexInSheet=143|OwnerPartId=-1|LineWidth=1|Color=8388608|LocationCount=2|X1=1010|Y1=280|X2=1010|Y2=300
|RECORD=27|IndexInSheet=144|OwnerPartId=-1|LineWidth=1|Color=8388608|LocationCount=2|X1=1010|Y1=330|X2=1010|Y2=370
|RECORD=27|IndexInSheet=145|OwnerPartId=-1|LineWidth=1|Color=8388608|LocationCount=2|X1=1260|Y1=380|X2=1260|Y2=280
|RECORD=27|IndexInSheet=146|OwnerPartId=-1|LineWidth=1|Color=8388608|LocationCount=2|X1=1260|Y1=410|X2=1260|Y2=430
|RECORD=27|IndexInSheet=147|OwnerPartId=-1|LineWidth=1|Color=8388608|LocationCount=2|X1=1260|Y1=460|X2=1260|Y2=550
|RECORD=27|IndexInSheet=148|OwnerPartId=-1|LineWidth=1|Color=8388608|LocationCount=2|X1=1310|Y1=380|X2=1310|Y2=280
|RECORD=27|IndexInSheet=149|OwnerPartId=-1|LineWidth=1|Color=8388608|LocationCount=2|X1=1310|Y1=410|X2=1310|Y2=430
|RECORD=27|IndexInSheet=150|OwnerPartId=-1|LineWidth=1|Color=8388608|LocationCount=2|X1=1360|Y1=380|X2=1360|Y2=280
|RECORD=27|IndexInSheet=151|OwnerPartId=-1|LineWidth=1|Color=8388608|LocationCount=2|X1=1360|Y1=410|X2=1360|Y2=430
|RECORD=27|IndexInSheet=152|OwnerPartId=-1|LineWidth=1|Color=8388608|LocationCount=2|X1=1460|Y1=380|X2=1460|Y2=280
|RECORD=27|IndexInSheet=153|OwnerPartId=-1|LineWidth=1|Color=8388608|LocationCount=2|X1=1460|Y1=410|X2=1460|Y2=430
|RECORD=27|IndexInSheet=154|OwnerPartId=-1|LineWidth=1|Color=8388608|LocationCount=2|X1=1620|Y1=300|X2=1620|Y2=280
|RECORD=27|IndexInSheet=155|OwnerPartId=-1|LineWidth=1|Color=8388608|LocationCount=2|X1=1620|Y1=370|X2=1620|Y2=350
|RECORD=27|IndexInSheet=156|OwnerPartId=-1|LineWidth=1|Color=8388608|LocationCount=2|X1=1620|Y1=430|X2=1620|Y2=440
|RECORD=1|LibReference=CAP|ComponentDescription=C0603X104K5RACAUTO|PartCount=2|DisplayModeCount=2|IndexInSheet=157|OwnerPartId=-1|Location.X=670|Location.Y=910|Orientation=1|CurrentPartId=1|SourceLibraryName=Altium Content Vault|TargetFileName=*|AreaColor=11599871|Color=128|PartIDLocked=F|DesignItemId=CMP-2006-00003-1|AllPinCount=2
|RECORD=2|OwnerIndex=1270|OwnerPartId=1|OwnerPartDisplayMode=1|FormalType=1|Electrical=4|PinConglomerate=35|PinLength=10|Location.X=680|Location.Y=910|Name=1|Designator=1|PinPropagationDelay=0.000000E+000
|RECORD=2|OwnerIndex=1270|OwnerPartId=1|OwnerPartDisplayMode=1|FormalType=1|Electrical=4|PinConglomerate=33|PinLength=10|Location.X=680|Location.Y=920|Name=2|Designator=2|PinPropagationDelay=0.000000E+000
|RECORD=13|OwnerIndex=1270|IsNotAccesible=T|IndexInSheet=2|OwnerPartId=1|OwnerPartDisplayMode=1|Location.X=688|Location.Y=910|Corner.X=672|Corner.Y=910|LineWidth=1|Color=16711680
|RECORD=13|OwnerIndex=1270|IsNotAccesible=T|IndexInSheet=3|OwnerPartId=1|OwnerPartDisplayMode=1|Location.X=680|Location.Y=914|Corner.X=680|Corner.Y=920|LineWidth=1|Color=16711680
|RECORD=12|OwnerIndex=1270|IsNotAccesible=T|IndexInSheet=4|OwnerPartId=1|OwnerPartDisplayMode=1|Location.X=680|Location.Y=930|Radius=16|LineWidth=1|StartAngle=241.000|EndAngle=270.000|Color=16711680
|RECORD=12|OwnerIndex=1270|IsNotAccesible=T|IndexInSheet=5|OwnerPartId=1|OwnerPartDisplayMode=1|Location.X=680|Location.Y=930|Radius=16|LineWidth=1|StartAngle=270.000|EndAngle=299.000|Color=16711680
|RECORD=2|OwnerIndex=1270|OwnerPartId=1|FormalType=1|Electrical=4|PinConglomerate=35|PinLength=10|Location.X=680|Location.Y=910|Name=1|Designator=1|PinPropagationDelay=0.000000E+000
|RECORD=2|OwnerIndex=1270|OwnerPartId=1|FormalType=1|Electrical=4|PinConglomerate=33|PinLength=10|Location.X=680|Location.Y=920|Name=2|Designator=2|PinPropagationDelay=0.000000E+000
|RECORD=13|OwnerIndex=1270|IsNotAccesible=T|IndexInSheet=8|OwnerPartId=1|Location.X=672|Location.Y=917|Corner.X=688|Corner.Y=917|LineWidth=1|Color=16711680
|RECORD=13|OwnerIndex=1270|IsNotAccesible=T|IndexInSheet=9|OwnerPartId=1|Location.X=688|Location.Y=913|Corner.X=672|Corner.Y=913|LineWidth=1|Color=16711680
|RECORD=6|OwnerIndex=1270|IsNotAccesible=T|IndexInSheet=10|OwnerPartId=1|LineWidth=1|Color=16711680|LocationCount=2|X1=680|Y1=910|X2=680|Y2=913
|RECORD=6|OwnerIndex=1270|IsNotAccesible=T|IndexInSheet=11|OwnerPartId=1|LineWidth=1|Color=16711680|LocationCount=2|X1=680|Y1=920|X2=680|Y2=917
|RECORD=41|OwnerIndex=1270|IndexInSheet=12|OwnerPartId=-1|Location.X=671|Location.Y=932|Color=8388608|FontID=1|IsHidden=T|Text=Kemet|Name=Manufacturer
|RECORD=41|OwnerIndex=1270|IndexInSheet=13|OwnerPartId=-1|Location.X=671|Location.Y=932|Color=8388608|FontID=1|IsHidden=T|Text=C0603X104K5RACAUTO|Name=Part Number
|RECORD=34|OwnerIndex=1270|IndexInSheet=-1|OwnerPartId=-1|Location.X=689|Location.Y=911|Color=8388608|FontID=3|Text=C2|Name=Designator|ReadOnlyState=1
|RECORD=41|OwnerIndex=1270|IndexInSheet=-1|OwnerPartId=-1|Location.X=689|Location.Y=901|Color=8388608|FontID=3|Text=0.1uF|Name=Comment
|RECORD=44|OwnerIndex=1270
|RECORD=45|OwnerIndex=1291|IndexInSheet=-1|Description=Chip Capacitor, 2-Leads, Body 1.60x0.80mm, IPC Low Density|UseComponentLibrary=T|ModelName=CAPC1608X87X45ML20T05|ModelType=PCBLIB|DatafileCount=1|ModelDatafileEntity0=CAPC1608X87X45ML20T05|ModelDatafileKind0=PCBLib|IsCurrent=T|DatalinksLocked=T|DatabaseDatalinksLocked=T
|RECORD=46|OwnerIndex=1292
|RECORD=48|OwnerIndex=1292
|RECORD=41|OwnerIndex=1294|IndexInSheet=-1|OwnerPartId=-1|Color=8388608|FontID=1|Text=2D|Name=Available Preview Images
|RECORD=45|OwnerIndex=1291|IndexInSheet=-1|Description=Chip Capacitor, 2-Leads, Body 1.60x0.80mm, IPC High Density|UseComponentLibrary=T|ModelName=CAPC1608X87X45LL20T05|ModelType=PCBLIB|DatafileCount=1|ModelDatafileEntity0=CAPC1608X87X45LL20T05|ModelDatafileKind0=PCBLib|DatalinksLocked=T|DatabaseDatalinksLocked=T
|RECORD=46|OwnerIndex=1296
|RECORD=48|OwnerIndex=1296
|RECORD=41|OwnerIndex=1298|IndexInSheet=-1|OwnerPartId=-1|Color=8388608|FontID=1|Text=2D|Name=Available Preview Images
|RECORD=45|OwnerIndex=1291|IndexInSheet=-1|Description=Chip Capacitor, 2-Leads, Body 1.60x0.80mm, IPC Medium Density|UseComponentLibrary=T|ModelName=CAPC1608X87X45NL20T05|ModelType=PCBLIB|DatafileCount=1|ModelDatafileEntity0=CAPC1608X87X45NL20T05|ModelDatafileKind0=PCBLib|DatalinksLocked=T|DatabaseDatalinksLocked=T
|RECORD=46|OwnerIndex=1300
|RECORD=48|OwnerIndex=1300
|RECORD=41|OwnerIndex=1302|IndexInSheet=-1|OwnerPartId=-1|Color=8388608|FontID=1|Text=2D|Name=Available Preview Images
|RECORD=1|LibReference=CAP|ComponentDescription=C0603X104K5RACAUTO|PartCount=2|DisplayModeCount=2|IndexInSheet=158|OwnerPartId=-1|Location.X=590|Location.Y=380|Orientation=1|CurrentPartId=1|SourceLibraryName=Altium Content Vault|TargetFileName=*|AreaColor=11599871|Color=128|PartIDLocked=F|DesignItemId=CMP-2006-00003-1|AllPinCount=2
|RECORD=2|OwnerIndex=1304|OwnerPartId=1|OwnerPartDisplayMode=1|FormalType=1|Electrical=4|PinConglomerate=35|PinLength=10|Location.X=600|Location.Y=380|Name=1|Designator=1|PinPropagationDelay=0.000000E+000
|RECORD=2|OwnerIndex=1304|OwnerPartId=1|OwnerPartDisplayMode=1|FormalType=1|Electrical=4|PinConglomerate=33|PinLength=10|Location.X=600|Location.Y=390|Name=2|Designator=2|PinPropagationDelay=0.000000E+000
|RECORD=13|OwnerIndex=1304|IsNotAccesible=T|IndexInSheet=2|OwnerPartId=1|OwnerPartDisplayMode=1|Location.X=608|Location.Y=380|Corner.X=592|Corner.Y=380|LineWidth=1|Color=16711680
|RECORD=13|OwnerIndex=1304|IsNotAccesible=T|IndexInSheet=3|OwnerPartId=1|OwnerPartDisplayMode=1|Location.X=600|Location.Y=384|Corner.X=600|Corner.Y=390|LineWidth=1|Color=16711680
|RECORD=12|OwnerIndex=1304|IsNotAccesible=T|IndexInSheet=4|OwnerPartId=1|OwnerPartDisplayMode=1|Location.X=600|Location.Y=400|Radius=16|LineWidth=1|StartAngle=241.000|EndAngle=270.000|Color=16711680
|RECORD=12|OwnerIndex=1304|IsNotAccesible=T|IndexInSheet=5|OwnerPartId=1|OwnerPartDisplayMode=1|Location.X=600|Location.Y=400|Radius=16|LineWidth=1|StartAngle=270.000|EndAngle=299.000|Color=16711680
|RECORD=2|OwnerIndex=1304|OwnerPartId=1|FormalType=1|Electrical=4|PinConglomerate=35|PinLength=10|Location.X=600|Location.Y=380|Name=1|Designator=1|PinPropagationDelay=0.000000E+000
|RECORD=2|OwnerIndex=1304|OwnerPartId=1|FormalType=1|Electrical=4|PinConglomerate=33|PinLength=10|Location.X=600|Location.Y=390|Name=2|Designator=2|PinPropagationDelay=0.000000E+000
|RECORD=13|OwnerIndex=1304|IsNotAccesible=T|IndexInSheet=8|OwnerPartId=1|Location.X=592|Location.Y=387|Corner.X=608|Corner.Y=387|LineWidth=1|Color=16711680
|RECORD=13|OwnerIndex=1304|IsNotAccesible=T|IndexInSheet=9|OwnerPartId=1|Location.X=608|Location.Y=383|Corner.X=592|Corner.Y=383|LineWidth=1|Color=16711680
|RECORD=6|OwnerIndex=1304|IsNotAccesible=T|IndexInSheet=10|OwnerPartId=1|LineWidth=1|Color=16711680|LocationCount=2|X1=600|Y1=380|X2=600|Y2=383
|RECORD=6|OwnerIndex=1304|IsNotAccesible=T|IndexInSheet=11|OwnerPartId=1|LineWidth=1|Color=16711680|LocationCount=2|X1=600|Y1=390|X2=600|Y2=387
|RECORD=41|OwnerIndex=1304|IndexInSheet=12|OwnerPartId=-1|Location.X=591|Location.Y=402|Color=8388608|FontID=1|IsHidden=T|Text=Kemet|Name=Manufacturer
|RECORD=41|OwnerIndex=1304|IndexInSheet=13|OwnerPartId=-1|Location.X=591|Location.Y=402|Color=8388608|FontID=1|IsHidden=T|Text=C0603X104K5RACAUTO|Name=Part Number
|RECORD=34|OwnerIndex=1304|IndexInSheet=-1|OwnerPartId=-1|Location.X=609|Location.Y=381|Color=8388608|FontID=3|Text=C15|Name=Designator|ReadOnlyState=1
|RECORD=41|OwnerIndex=1304|IndexInSheet=-1|OwnerPartId=-1|Location.X=609|Location.Y=371|Color=8388608|FontID=3|Text=0.1uF|Name=Comment
|RECORD=44|OwnerIndex=1304
|RECORD=45|OwnerIndex=1325|IndexInSheet=-1|Description=Chip Capacitor, 2-Leads, Body 1.60x0.80mm, IPC Low Density|UseComponentLibrary=T|ModelName=CAPC1608X87X45ML20T05|ModelType=PCBLIB|DatafileCount=1|ModelDatafileEntity0=CAPC1608X87X45ML20T05|ModelDatafileKind0=PCBLib|IsCurrent=T|DatalinksLocked=T|DatabaseDatalinksLocked=T
|RECORD=46|OwnerIndex=1326
|RECORD=48|OwnerIndex=1326
|RECORD=41|OwnerIndex=1328|IndexInSheet=-1|OwnerPartId=-1|Color=8388608|FontID=1|Text=2D|Name=Available Preview Images
|RECORD=45|OwnerIndex=1325|IndexInSheet=-1|Description=Chip Capacitor, 2-Leads, Body 1.60x0.80mm, IPC High Density|UseComponentLibrary=T|ModelName=CAPC1608X87X45LL20T05|ModelType=PCBLIB|DatafileCount=1|ModelDatafileEntity0=CAPC1608X87X45LL20T05|ModelDatafileKind0=PCBLib|DatalinksLocked=T|DatabaseDatalinksLocked=T
|RECORD=46|OwnerIndex=1330
|RECORD=48|OwnerIndex=1330
|RECORD=41|OwnerIndex=1332|IndexInSheet=-1|OwnerPartId=-1|Color=8388608|FontID=1|Text=2D|Name=Available Preview Images
|RECORD=45|OwnerIndex=1325|IndexInSheet=-1|Description=Chip Capacitor, 2-Leads, Body 1.60x0.80mm, IPC Medium Density|UseComponentLibrary=T|ModelName=CAPC1608X87X45NL20T05|ModelType=PCBLIB|DatafileCount=1|ModelDatafileEntity0=CAPC1608X87X45NL20T05|ModelDatafileKind0=PCBLib|DatalinksLocked=T|DatabaseDatalinksLocked=T
|RECORD=46|OwnerIndex=1334
|RECORD=48|OwnerIndex=1334
|RECORD=41|OwnerIndex=1336|IndexInSheet=-1|OwnerPartId=-1|Color=8388608|FontID=1|Text=2D|Name=Available Preview Images
|RECORD=1|LibReference=CAP|ComponentDescription=C0603X104K5RACAUTO|PartCount=2|DisplayModeCount=2|IndexInSheet=159|OwnerPartId=-1|Location.X=640|Location.Y=380|Orientation=1|CurrentPartId=1|SourceLibraryName=Altium Content Vault|TargetFileName=*|AreaColor=11599871|Color=128|PartIDLocked=F|DesignItemId=CMP-2006-00003-1|AllPinCount=2
|RECORD=2|OwnerIndex=1338|OwnerPartId=1|OwnerPartDisplayMode=1|FormalType=1|Electrical=4|PinConglomerate=35|PinLength=10|Location.X=650|Location.Y=380|Name=1|Designator=1|PinPropagationDelay=0.000000E+000
|RECORD=2|OwnerIndex=1338|OwnerPartId=1|OwnerPartDisplayMode=1|FormalType=1|Electrical=4|PinConglomerate=33|PinLength=10|Location.X=650|Location.Y=390|Name=2|Designator=2|PinPropagationDelay=0.000000E+000
|RECORD=13|OwnerIndex=1338|IsNotAccesible=T|IndexInSheet=2|OwnerPartId=1|OwnerPartDisplayMode=1|Location.X=658|Location.Y=380|Corner.X=642|Corner.Y=380|LineWidth=1|Color=16711680
|RECORD=13|OwnerIndex=1338|IsNotAccesible=T|IndexInSheet=3|OwnerPartId=1|OwnerPartDisplayMode=1|Location.X=650|Location.Y=384|Corner.X=650|Corner.Y=390|LineWidth=1|Color=16711680
|RECORD=12|OwnerIndex=1338|IsNotAccesible=T|IndexInSheet=4|OwnerPartId=1|OwnerPartDisplayMode=1|Location.X=650|Location.Y=400|Radius=16|LineWidth=1|StartAngle=241.000|EndAngle=270.000|Color=16711680
|RECORD=12|OwnerIndex=1338|IsNotAccesible=T|IndexInSheet=5|OwnerPartId=1|OwnerPartDisplayMode=1|Location.X=650|Location.Y=400|Radius=16|LineWidth=1|StartAngle=270.000|EndAngle=299.000|Color=16711680
|RECORD=2|OwnerIndex=1338|OwnerPartId=1|FormalType=1|Electrical=4|PinConglomerate=35|PinLength=10|Location.X=650|Location.Y=380|Name=1|Designator=1|PinPropagationDelay=0.000000E+000
|RECORD=2|OwnerIndex=1338|OwnerPartId=1|FormalType=1|Electrical=4|PinConglomerate=33|PinLength=10|Location.X=650|Location.Y=390|Name=2|Designator=2|PinPropagationDelay=0.000000E+000
|RECORD=13|OwnerIndex=1338|IsNotAccesible=T|IndexInSheet=8|OwnerPartId=1|Location.X=642|Location.Y=387|Corner.X=658|Corner.Y=387|LineWidth=1|Color=16711680
|RECORD=13|OwnerIndex=1338|IsNotAccesible=T|IndexInSheet=9|OwnerPartId=1|Location.X=658|Location.Y=383|Corner.X=642|Corner.Y=383|LineWidth=1|Color=16711680
|RECORD=6|OwnerIndex=1338|IsNotAccesible=T|IndexInSheet=10|OwnerPartId=1|LineWidth=1|Color=16711680|LocationCount=2|X1=650|Y1=380|X2=650|Y2=383
|RECORD=6|OwnerIndex=1338|IsNotAccesible=T|IndexInSheet=11|OwnerPartId=1|LineWidth=1|Color=16711680|LocationCount=2|X1=650|Y1=390|X2=650|Y2=387
|RECORD=41|OwnerIndex=1338|IndexInSheet=12|OwnerPartId=-1|Location.X=641|Location.Y=402|Color=8388608|FontID=1|IsHidden=T|Text=Kemet|Name=Manufacturer
|RECORD=41|OwnerIndex=1338|IndexInSheet=13|OwnerPartId=-1|Location.X=641|Location.Y=402|Color=8388608|FontID=1|IsHidden=T|Text=C0603X104K5RACAUTO|Name=Part Number
|RECORD=34|OwnerIndex=1338|IndexInSheet=-1|OwnerPartId=-1|Location.X=659|Location.Y=381|Color=8388608|FontID=3|Text=C16|Name=Designator|ReadOnlyState=1
|RECORD=41|OwnerIndex=1338|IndexInSheet=-1|OwnerPartId=-1|Location.X=659|Location.Y=371|Color=8388608|FontID=3|Text=0.1uF|Name=Comment
|RECORD=44|OwnerIndex=1338
|RECORD=45|OwnerIndex=1359|IndexInSheet=-1|Description=Chip Capacitor, 2-Leads, Body 1.60x0.80mm, IPC Low Density|UseComponentLibrary=T|ModelName=CAPC1608X87X45ML20T05|ModelType=PCBLIB|DatafileCount=1|ModelDatafileEntity0=CAPC1608X87X45ML20T05|ModelDatafileKind0=PCBLib|IsCurrent=T|DatalinksLocked=T|DatabaseDatalinksLocked=T
|RECORD=46|OwnerIndex=1360
|RECORD=48|OwnerIndex=1360
|RECORD=41|OwnerIndex=1362|IndexInSheet=-1|OwnerPartId=-1|Color=8388608|FontID=1|Text=2D|Name=Available Preview Images
|RECORD=45|OwnerIndex=1359|IndexInSheet=-1|Description=Chip Capacitor, 2-Leads, Body 1.60x0.80mm, IPC High Density|UseComponentLibrary=T|ModelName=CAPC1608X87X45LL20T05|ModelType=PCBLIB|DatafileCount=1|ModelDatafileEntity0=CAPC1608X87X45LL20T05|ModelDatafileKind0=PCBLib|DatalinksLocked=T|DatabaseDatalinksLocked=T
|RECORD=46|OwnerIndex=1364
|RECORD=48|OwnerIndex=1364
|RECORD=41|OwnerIndex=1366|IndexInSheet=-1|OwnerPartId=-1|Color=8388608|FontID=1|Text=2D|Name=Available Preview Images
|RECORD=45|OwnerIndex=1359|IndexInSheet=-1|Description=Chip Capacitor, 2-Leads, Body 1.60x0.80mm, IPC Medium Density|UseComponentLibrary=T|ModelName=CAPC1608X87X45NL20T05|ModelType=PCBLIB|DatafileCount=1|ModelDatafileEntity0=CAPC1608X87X45NL20T05|ModelDatafileKind0=PCBLib|DatalinksLocked=T|DatabaseDatalinksLocked=T
|RECORD=46|OwnerIndex=1368
|RECORD=48|OwnerIndex=1368
|RECORD=41|OwnerIndex=1370|IndexInSheet=-1|OwnerPartId=-1|Color=8388608|FontID=1|Text=2D|Name=Available Preview Images
|RECORD=1|LibReference=CAP|ComponentDescription=C0603X104K5RACAUTO|PartCount=2|DisplayModeCount=2|IndexInSheet=160|OwnerPartId=-1|Location.X=690|Location.Y=380|Orientation=1|CurrentPartId=1|SourceLibraryName=Altium Content Vault|TargetFileName=*|AreaColor=11599871|Color=128|PartIDLocked=F|DesignItemId=CMP-2006-00003-1|AllPinCount=2
|RECORD=2|OwnerIndex=1372|OwnerPartId=1|OwnerPartDisplayMode=1|FormalType=1|Electrical=4|PinConglomerate=35|PinLength=10|Location.X=700|Location.Y=380|Name=1|Designator=1|PinPropagationDelay=0.000000E+000
|RECORD=2|OwnerIndex=1372|OwnerPartId=1|OwnerPartDisplayMode=1|FormalType=1|Electrical=4|PinConglomerate=33|PinLength=10|Location.X=700|Location.Y=390|Name=2|Designator=2|PinPropagationDelay=0.000000E+000
|RECORD=13|OwnerIndex=1372|IsNotAccesible=T|IndexInSheet=2|OwnerPartId=1|OwnerPartDisplayMode=1|Location.X=708|Location.Y=380|Corner.X=692|Corner.Y=380|LineWidth=1|Color=16711680
|RECORD=13|OwnerIndex=1372|IsNotAccesible=T|IndexInSheet=3|OwnerPartId=1|OwnerPartDisplayMode=1|Location.X=700|Location.Y=384|Corner.X=700|Corner.Y=390|LineWidth=1|Color=16711680
|RECORD=12|OwnerIndex=1372|IsNotAccesible=T|IndexInSheet=4|OwnerPartId=1|OwnerPartDisplayMode=1|Location.X=700|Location.Y=400|Radius=16|LineWidth=1|StartAngle=241.000|EndAngle=270.000|Color=16711680
|RECORD=12|OwnerIndex=1372|IsNotAccesible=T|IndexInSheet=5|OwnerPartId=1|OwnerPartDisplayMode=1|Location.X=700|Location.Y=400|Radius=16|LineWidth=1|StartAngle=270.000|EndAngle=299.000|Color=16711680
|RECORD=2|OwnerIndex=1372|OwnerPartId=1|FormalType=1|Electrical=4|PinConglomerate=35|PinLength=10|Location.X=700|Location.Y=380|Name=1|Designator=1|PinPropagationDelay=0.000000E+000
|RECORD=2|OwnerIndex=1372|OwnerPartId=1|FormalType=1|Electrical=4|PinConglomerate=33|PinLength=10|Location.X=700|Location.Y=390|Name=2|Designator=2|PinPropagationDelay=0.000000E+000
|RECORD=13|OwnerIndex=1372|IsNotAccesible=T|IndexInSheet=8|OwnerPartId=1|Location.X=692|Location.Y=387|Corner.X=708|Corner.Y=387|LineWidth=1|Color=16711680
|RECORD=13|OwnerIndex=1372|IsNotAccesible=T|IndexInSheet=9|OwnerPartId=1|Location.X=708|Location.Y=383|Corner.X=692|Corner.Y=383|LineWidth=1|Color=16711680
|RECORD=6|OwnerIndex=1372|IsNotAccesible=T|IndexInSheet=10|OwnerPartId=1|LineWidth=1|Color=16711680|LocationCount=2|X1=700|Y1=380|X2=700|Y2=383
|RECORD=6|OwnerIndex=1372|IsNotAccesible=T|IndexInSheet=11|OwnerPartId=1|LineWidth=1|Color=16711680|LocationCount=2|X1=700|Y1=390|X2=700|Y2=387
|RECORD=41|OwnerIndex=1372|IndexInSheet=12|OwnerPartId=-1|Location.X=691|Location.Y=402|Color=8388608|FontID=1|IsHidden=T|Text=Kemet|Name=Manufacturer
|RECORD=41|OwnerIndex=1372|IndexInSheet=13|OwnerPartId=-1|Location.X=691|Location.Y=402|Color=8388608|FontID=1|IsHidden=T|Text=C0603X104K5RACAUTO|Name=Part Number
|RECORD=34|OwnerIndex=1372|IndexInSheet=-1|OwnerPartId=-1|Location.X=709|Location.Y=381|Color=8388608|FontID=3|Text=C17|Name=Designator|ReadOnlyState=1
|RECORD=41|OwnerIndex=1372|IndexInSheet=-1|OwnerPartId=-1|Location.X=709|Location.Y=371|Color=8388608|FontID=3|Text=0.1uF|Name=Comment
|RECORD=44|OwnerIndex=1372
|RECORD=45|OwnerIndex=1393|IndexInSheet=-1|Description=Chip Capacitor, 2-Leads, Body 1.60x0.80mm, IPC Low Density|UseComponentLibrary=T|ModelName=CAPC1608X87X45ML20T05|ModelType=PCBLIB|DatafileCount=1|ModelDatafileEntity0=CAPC1608X87X45ML20T05|ModelDatafileKind0=PCBLib|IsCurrent=T|DatalinksLocked=T|DatabaseDatalinksLocked=T
|RECORD=46|OwnerIndex=1394
|RECORD=48|OwnerIndex=1394
|RECORD=41|OwnerIndex=1396|IndexInSheet=-1|OwnerPartId=-1|Color=8388608|FontID=1|Text=2D|Name=Available Preview Images
|RECORD=45|OwnerIndex=1393|IndexInSheet=-1|Description=Chip Capacitor, 2-Leads, Body 1.60x0.80mm, IPC High Density|UseComponentLibrary=T|ModelName=CAPC1608X87X45LL20T05|ModelType=PCBLIB|DatafileCount=1|ModelDatafileEntity0=CAPC1608X87X45LL20T05|ModelDatafileKind0=PCBLib|DatalinksLocked=T|DatabaseDatalinksLocked=T
|RECORD=46|OwnerIndex=1398
|RECORD=48|OwnerIndex=1398
|RECORD=41|OwnerIndex=1400|IndexInSheet=-1|OwnerPartId=-1|Color=8388608|FontID=1|Text=2D|Name=Available Preview Images
|RECORD=45|OwnerIndex=1393|IndexInSheet=-1|Description=Chip Capacitor, 2-Leads, Body 1.60x0.80mm, IPC Medium Density|UseComponentLibrary=T|ModelName=CAPC1608X87X45NL20T05|ModelType=PCBLIB|DatafileCount=1|ModelDatafileEntity0=CAPC1608X87X45NL20T05|ModelDatafileKind0=PCBLib|DatalinksLocked=T|DatabaseDatalinksLocked=T
|RECORD=46|OwnerIndex=1402
|RECORD=48|OwnerIndex=1402
|RECORD=41|OwnerIndex=1404|IndexInSheet=-1|OwnerPartId=-1|Color=8388608|FontID=1|Text=2D|Name=Available Preview Images
|RECORD=1|LibReference=CAP|ComponentDescription=C0603X104K5RACAUTO|PartCount=2|DisplayModeCount=2|IndexInSheet=161|OwnerPartId=-1|Location.X=740|Location.Y=380|Orientation=1|CurrentPartId=1|SourceLibraryName=Altium Content Vault|TargetFileName=*|AreaColor=11599871|Color=128|PartIDLocked=F|DesignItemId=CMP-2006-00003-1|AllPinCount=2
|RECORD=2|OwnerIndex=1406|OwnerPartId=1|OwnerPartDisplayMode=1|FormalType=1|Electrical=4|PinConglomerate=35|PinLength=10|Location.X=750|Location.Y=380|Name=1|Designator=1|PinPropagationDelay=0.000000E+000
|RECORD=2|OwnerIndex=1406|OwnerPartId=1|OwnerPartDisplayMode=1|FormalType=1|Electrical=4|PinConglomerate=33|PinLength=10|Location.X=750|Location.Y=390|Name=2|Designator=2|PinPropagationDelay=0.000000E+000
|RECORD=13|OwnerIndex=1406|IsNotAccesible=T|IndexInSheet=2|OwnerPartId=1|OwnerPartDisplayMode=1|Location.X=758|Location.Y=380|Corner.X=742|Corner.Y=380|LineWidth=1|Color=16711680
|RECORD=13|OwnerIndex=1406|IsNotAccesible=T|IndexInSheet=3|OwnerPartId=1|OwnerPartDisplayMode=1|Location.X=750|Location.Y=384|Corner.X=750|Corner.Y=390|LineWidth=1|Color=16711680
|RECORD=12|OwnerIndex=1406|IsNotAccesible=T|IndexInSheet=4|OwnerPartId=1|OwnerPartDisplayMode=1|Location.X=750|Location.Y=400|Radius=16|LineWidth=1|StartAngle=241.000|EndAngle=270.000|Color=16711680
|RECORD=12|OwnerIndex=1406|IsNotAccesible=T|IndexInSheet=5|OwnerPartId=1|OwnerPartDisplayMode=1|Location.X=750|Location.Y=400|Radius=16|LineWidth=1|StartAngle=270.000|EndAngle=299.000|Color=16711680
|RECORD=2|OwnerIndex=1406|OwnerPartId=1|FormalType=1|Electrical=4|PinConglomerate=35|PinLength=10|Location.X=750|Location.Y=380|Name=1|Designator=1|PinPropagationDelay=0.000000E+000
|RECORD=2|OwnerIndex=1406|OwnerPartId=1|FormalType=1|Electrical=4|PinConglomerate=33|PinLength=10|Location.X=750|Location.Y=390|Name=2|Designator=2|PinPropagationDelay=0.000000E+000
|RECORD=13|OwnerIndex=1406|IsNotAccesible=T|IndexInSheet=8|OwnerPartId=1|Location.X=742|Location.Y=387|Corner.X=758|Corner.Y=387|LineWidth=1|Color=16711680
|RECORD=13|OwnerIndex=1406|IsNotAccesible=T|IndexInSheet=9|OwnerPartId=1|Location.X=758|Location.Y=383|Corner.X=742|Corner.Y=383|LineWidth=1|Color=16711680
|RECORD=6|OwnerIndex=1406|IsNotAccesible=T|IndexInSheet=10|OwnerPartId=1|LineWidth=1|Color=16711680|LocationCount=2|X1=750|Y1=380|X2=750|Y2=383
|RECORD=6|OwnerIndex=1406|IsNotAccesible=T|IndexInSheet=11|OwnerPartId=1|LineWidth=1|Color=16711680|LocationCount=2|X1=750|Y1=390|X2=750|Y2=387
|RECORD=41|OwnerIndex=1406|IndexInSheet=12|OwnerPartId=-1|Location.X=741|Location.Y=402|Color=8388608|FontID=1|IsHidden=T|Text=Kemet|Name=Manufacturer
|RECORD=41|OwnerIndex=1406|IndexInSheet=13|OwnerPartId=-1|Location.X=741|Location.Y=402|Color=8388608|FontID=1|IsHidden=T|Text=C0603X104K5RACAUTO|Name=Part Number
|RECORD=34|OwnerIndex=1406|IndexInSheet=-1|OwnerPartId=-1|Location.X=759|Location.Y=381|Color=8388608|FontID=3|Text=C18|Name=Designator|ReadOnlyState=1
|RECORD=41|OwnerIndex=1406|IndexInSheet=-1|OwnerPartId=-1|Location.X=759|Location.Y=371|Color=8388608|FontID=3|Text=0.1uF|Name=Comment
|RECORD=44|OwnerIndex=1406
|RECORD=45|OwnerIndex=1427|IndexInSheet=-1|Description=Chip Capacitor, 2-Leads, Body 1.60x0.80mm, IPC Low Density|UseComponentLibrary=T|ModelName=CAPC1608X87X45ML20T05|ModelType=PCBLIB|DatafileCount=1|ModelDatafileEntity0=CAPC1608X87X45ML20T05|ModelDatafileKind0=PCBLib|IsCurrent=T|DatalinksLocked=T|DatabaseDatalinksLocked=T
|RECORD=46|OwnerIndex=1428
|RECORD=48|OwnerIndex=1428
|RECORD=41|OwnerIndex=1430|IndexInSheet=-1|OwnerPartId=-1|Color=8388608|FontID=1|Text=2D|Name=Available Preview Images
|RECORD=45|OwnerIndex=1427|IndexInSheet=-1|Description=Chip Capacitor, 2-Leads, Body 1.60x0.80mm, IPC High Density|UseComponentLibrary=T|ModelName=CAPC1608X87X45LL20T05|ModelType=PCBLIB|DatafileCount=1|ModelDatafileEntity0=CAPC1608X87X45LL20T05|ModelDatafileKind0=PCBLib|DatalinksLocked=T|DatabaseDatalinksLocked=T
|RECORD=46|OwnerIndex=1432
|RECORD=48|OwnerIndex=1432
|RECORD=41|OwnerIndex=1434|IndexInSheet=-1|OwnerPartId=-1|Color=8388608|FontID=1|Text=2D|Name=Available Preview Images
|RECORD=45|OwnerIndex=1427|IndexInSheet=-1|Description=Chip Capacitor, 2-Leads, Body 1.60x0.80mm, IPC Medium Density|UseComponentLibrary=T|ModelName=CAPC1608X87X45NL20T05|ModelType=PCBLIB|DatafileCount=1|ModelDatafileEntity0=CAPC1608X87X45NL20T05|ModelDatafileKind0=PCBLib|DatalinksLocked=T|DatabaseDatalinksLocked=T
|RECORD=46|OwnerIndex=1436
|RECORD=48|OwnerIndex=1436
|RECORD=41|OwnerIndex=1438|IndexInSheet=-1|OwnerPartId=-1|Color=8388608|FontID=1|Text=2D|Name=Available Preview Images
|RECORD=1|LibReference=CAP|ComponentDescription=C0603X104K5RACAUTO|PartCount=2|DisplayModeCount=2|IndexInSheet=162|OwnerPartId=-1|Location.X=90|Location.Y=370|Orientation=1|CurrentPartId=1|SourceLibraryName=Altium Content Vault|TargetFileName=*|AreaColor=11599871|Color=128|PartIDLocked=F|DesignItemId=CMP-2006-00003-1|AllPinCount=2
|RECORD=2|OwnerIndex=1440|OwnerPartId=1|OwnerPartDisplayMode=1|FormalType=1|Electrical=4|PinConglomerate=35|PinLength=10|Location.X=100|Location.Y=370|Name=1|Designator=1|PinPropagationDelay=0.000000E+000
|RECORD=2|OwnerIndex=1440|OwnerPartId=1|OwnerPartDisplayMode=1|FormalType=1|Electrical=4|PinConglomerate=33|PinLength=10|Location.X=100|Location.Y=380|Name=2|Designator=2|PinPropagationDelay=0.000000E+000
|RECORD=13|OwnerIndex=1440|IsNotAccesible=T|IndexInSheet=2|OwnerPartId=1|OwnerPartDisplayMode=1|Location.X=108|Location.Y=370|Corner.X=92|Corner.Y=370|LineWidth=1|Color=16711680
|RECORD=13|OwnerIndex=1440|IsNotAccesible=T|IndexInSheet=3|OwnerPartId=1|OwnerPartDisplayMode=1|Location.X=100|Location.Y=374|Corner.X=100|Corner.Y=380|LineWidth=1|Color=16711680
|RECORD=12|OwnerIndex=1440|IsNotAccesible=T|IndexInSheet=4|OwnerPartId=1|OwnerPartDisplayMode=1|Location.X=100|Location.Y=390|Radius=16|LineWidth=1|StartAngle=241.000|EndAngle=270.000|Color=16711680
|RECORD=12|OwnerIndex=1440|IsNotAccesible=T|IndexInSheet=5|OwnerPartId=1|OwnerPartDisplayMode=1|Location.X=100|Location.Y=390|Radius=16|LineWidth=1|StartAngle=270.000|EndAngle=299.000|Color=16711680
|RECORD=2|OwnerIndex=1440|OwnerPartId=1|FormalType=1|Electrical=4|PinConglomerate=35|PinLength=10|Location.X=100|Location.Y=370|Name=1|Designator=1|PinPropagationDelay=0.000000E+000
|RECORD=2|OwnerIndex=1440|OwnerPartId=1|FormalType=1|Electrical=4|PinConglomerate=33|PinLength=10|Location.X=100|Location.Y=380|Name=2|Designator=2|PinPropagationDelay=0.000000E+000
|RECORD=13|OwnerIndex=1440|IsNotAccesible=T|IndexInSheet=8|OwnerPartId=1|Location.X=92|Location.Y=377|Corner.X=108|Corner.Y=377|LineWidth=1|Color=16711680
|RECORD=13|OwnerIndex=1440|IsNotAccesible=T|IndexInSheet=9|OwnerPartId=1|Location.X=108|Location.Y=373|Corner.X=92|Corner.Y=373|LineWidth=1|Color=16711680
|RECORD=6|OwnerIndex=1440|IsNotAccesible=T|IndexInSheet=10|OwnerPartId=1|LineWidth=1|Color=16711680|LocationCount=2|X1=100|Y1=370|X2=100|Y2=373
|RECORD=6|OwnerIndex=1440|IsNotAccesible=T|IndexInSheet=11|OwnerPartId=1|LineWidth=1|Color=16711680|LocationCount=2|X1=100|Y1=380|X2=100|Y2=377
|RECORD=41|OwnerIndex=1440|IndexInSheet=12|OwnerPartId=-1|Location.X=91|Location.Y=392|Color=8388608|FontID=1|IsHidden=T|Text=Kemet|Name=Manufacturer
|RECORD=41|OwnerIndex=1440|IndexInSheet=13|OwnerPartId=-1|Location.X=91|Location.Y=392|Color=8388608|FontID=1|IsHidden=T|Text=C0603X104K5RACAUTO|Name=Part Number
|RECORD=34|OwnerIndex=1440|IndexInSheet=-1|OwnerPartId=-1|Location.X=109|Location.Y=371|Color=8388608|FontID=3|Text=C19|Name=Designator|ReadOnlyState=1
|RECORD=41|OwnerIndex=1440|IndexInSheet=-1|OwnerPartId=-1|Location.X=109|Location.Y=361|Color=8388608|FontID=3|Text=0.1uF|Name=Comment
|RECORD=44|OwnerIndex=1440
|RECORD=45|OwnerIndex=1461|IndexInSheet=-1|Description=Chip Capacitor, 2-Leads, Body 1.60x0.80mm, IPC Low Density|UseComponentLibrary=T|ModelName=CAPC1608X87X45ML20T05|ModelType=PCBLIB|DatafileCount=1|ModelDatafileEntity0=CAPC1608X87X45ML20T05|ModelDatafileKind0=PCBLib|IsCurrent=T|DatalinksLocked=T|DatabaseDatalinksLocked=T
|RECORD=46|OwnerIndex=1462
|RECORD=48|OwnerIndex=1462
|RECORD=41|OwnerIndex=1464|IndexInSheet=-1|OwnerPartId=-1|Color=8388608|FontID=1|Text=2D|Name=Available Preview Images
|RECORD=45|OwnerIndex=1461|IndexInSheet=-1|Description=Chip Capacitor, 2-Leads, Body 1.60x0.80mm, IPC High Density|UseComponentLibrary=T|ModelName=CAPC1608X87X45LL20T05|ModelType=PCBLIB|DatafileCount=1|ModelDatafileEntity0=CAPC1608X87X45LL20T05|ModelDatafileKind0=PCBLib|DatalinksLocked=T|DatabaseDatalinksLocked=T
|RECORD=46|OwnerIndex=1466
|RECORD=48|OwnerIndex=1466
|RECORD=41|OwnerIndex=1468|IndexInSheet=-1|OwnerPartId=-1|Color=8388608|FontID=1|Text=2D|Name=Available Preview Images
|RECORD=45|OwnerIndex=1461|IndexInSheet=-1|Description=Chip Capacitor, 2-Leads, Body 1.60x0.80mm, IPC Medium Density|UseComponentLibrary=T|ModelName=CAPC1608X87X45NL20T05|ModelType=PCBLIB|DatafileCount=1|ModelDatafileEntity0=CAPC1608X87X45NL20T05|ModelDatafileKind0=PCBLib|DatalinksLocked=T|DatabaseDatalinksLocked=T
|RECORD=46|OwnerIndex=1470
|RECORD=48|OwnerIndex=1470
|RECORD=41|OwnerIndex=1472|IndexInSheet=-1|OwnerPartId=-1|Color=8388608|FontID=1|Text=2D|Name=Available Preview Images
|RECORD=1|LibReference=CAP|ComponentDescription=C0603X104K5RACAUTO|PartCount=2|DisplayModeCount=2|IndexInSheet=163|OwnerPartId=-1|Location.X=870|Location.Y=340|Orientation=1|CurrentPartId=1|SourceLibraryName=Altium Content Vault|TargetFileName=*|AreaColor=11599871|Color=128|PartIDLocked=F|DesignItemId=CMP-2006-00003-1|AllPinCount=2
|RECORD=2|OwnerIndex=1474|OwnerPartId=1|OwnerPartDisplayMode=1|FormalType=1|Electrical=4|PinConglomerate=35|PinLength=10|Location.X=880|Location.Y=340|Name=1|Designator=1|PinPropagationDelay=0.000000E+000
|RECORD=2|OwnerIndex=1474|OwnerPartId=1|OwnerPartDisplayMode=1|FormalType=1|Electrical=4|PinConglomerate=33|PinLength=10|Location.X=880|Location.Y=350|Name=2|Designator=2|PinPropagationDelay=0.000000E+000
|RECORD=13|OwnerIndex=1474|IsNotAccesible=T|IndexInSheet=2|OwnerPartId=1|OwnerPartDisplayMode=1|Location.X=888|Location.Y=340|Corner.X=872|Corner.Y=340|LineWidth=1|Color=16711680
|RECORD=13|OwnerIndex=1474|IsNotAccesible=T|IndexInSheet=3|OwnerPartId=1|OwnerPartDisplayMode=1|Location.X=880|Location.Y=344|Corner.X=880|Corner.Y=350|LineWidth=1|Color=16711680
|RECORD=12|OwnerIndex=1474|IsNotAccesible=T|IndexInSheet=4|OwnerPartId=1|OwnerPartDisplayMode=1|Location.X=880|Location.Y=360|Radius=16|LineWidth=1|StartAngle=241.000|EndAngle=270.000|Color=16711680
|RECORD=12|OwnerIndex=1474|IsNotAccesible=T|IndexInSheet=5|OwnerPartId=1|OwnerPartDisplayMode=1|Location.X=880|Location.Y=360|Radius=16|LineWidth=1|StartAngle=270.000|EndAngle=299.000|Color=16711680
|RECORD=2|OwnerIndex=1474|OwnerPartId=1|FormalType=1|Electrical=4|PinConglomerate=35|PinLength=10|Location.X=880|Location.Y=340|Name=1|Designator=1|PinPropagationDelay=0.000000E+000
|RECORD=2|OwnerIndex=1474|OwnerPartId=1|FormalType=1|Electrical=4|PinConglomerate=33|PinLength=10|Location.X=880|Location.Y=350|Name=2|Designator=2|PinPropagationDelay=0.000000E+000
|RECORD=13|OwnerIndex=1474|IsNotAccesible=T|IndexInSheet=8|OwnerPartId=1|Location.X=872|Location.Y=347|Corner.X=888|Corner.Y=347|LineWidth=1|Color=16711680
|RECORD=13|OwnerIndex=1474|IsNotAccesible=T|IndexInSheet=9|OwnerPartId=1|Location.X=888|Location.Y=343|Corner.X=872|Corner.Y=343|LineWidth=1|Color=16711680
|RECORD=6|OwnerIndex=1474|IsNotAccesible=T|IndexInSheet=10|OwnerPartId=1|LineWidth=1|Color=16711680|LocationCount=2|X1=880|Y1=340|X2=880|Y2=343
|RECORD=6|OwnerIndex=1474|IsNotAccesible=T|IndexInSheet=11|OwnerPartId=1|LineWidth=1|Color=16711680|LocationCount=2|X1=880|Y1=350|X2=880|Y2=347
|RECORD=41|OwnerIndex=1474|IndexInSheet=12|OwnerPartId=-1|Location.X=871|Location.Y=362|Color=8388608|FontID=1|IsHidden=T|Text=Kemet|Name=Manufacturer
|RECORD=41|OwnerIndex=1474|IndexInSheet=13|OwnerPartId=-1|Location.X=871|Location.Y=362|Color=8388608|FontID=1|IsHidden=T|Text=C0603X104K5RACAUTO|Name=Part Number
|RECORD=34|OwnerIndex=1474|IndexInSheet=-1|OwnerPartId=-1|Location.X=889|Location.Y=341|Color=8388608|FontID=3|Text=C21|Name=Designator|ReadOnlyState=1
|RECORD=41|OwnerIndex=1474|IndexInSheet=-1|OwnerPartId=-1|Location.X=889|Location.Y=331|Color=8388608|FontID=3|Text=0.1uF|Name=Comment
|RECORD=44|OwnerIndex=1474
|RECORD=45|OwnerIndex=1495|IndexInSheet=-1|Description=Chip Capacitor, 2-Leads, Body 1.60x0.80mm, IPC Low Density|UseComponentLibrary=T|ModelName=CAPC1608X87X45ML20T05|ModelType=PCBLIB|DatafileCount=1|ModelDatafileEntity0=CAPC1608X87X45ML20T05|ModelDatafileKind0=PCBLib|IsCurrent=T|DatalinksLocked=T|DatabaseDatalinksLocked=T
|RECORD=46|OwnerIndex=1496
|RECORD=48|OwnerIndex=1496
|RECORD=41|OwnerIndex=1498|IndexInSheet=-1|OwnerPartId=-1|Color=8388608|FontID=1|Text=2D|Name=Available Preview Images
|RECORD=45|OwnerIndex=1495|IndexInSheet=-1|Description=Chip Capacitor, 2-Leads, Body 1.60x0.80mm, IPC High Density|UseComponentLibrary=T|ModelName=CAPC1608X87X45LL20T05|ModelType=PCBLIB|DatafileCount=1|ModelDatafileEntity0=CAPC1608X87X45LL20T05|ModelDatafileKind0=PCBLib|DatalinksLocked=T|DatabaseDatalinksLocked=T
|RECORD=46|OwnerIndex=1500
|RECORD=48|OwnerIndex=1500
|RECORD=41|OwnerIndex=1502|IndexInSheet=-1|OwnerPartId=-1|Color=8388608|FontID=1|Text=2D|Name=Available Preview Images
|RECORD=45|OwnerIndex=1495|IndexInSheet=-1|Description=Chip Capacitor, 2-Leads, Body 1.60x0.80mm, IPC Medium Density|UseComponentLibrary=T|ModelName=CAPC1608X87X45NL20T05|ModelType=PCBLIB|DatafileCount=1|ModelDatafileEntity0=CAPC1608X87X45NL20T05|ModelDatafileKind0=PCBLib|DatalinksLocked=T|DatabaseDatalinksLocked=T
|RECORD=46|OwnerIndex=1504
|RECORD=48|OwnerIndex=1504
|RECORD=41|OwnerIndex=1506|IndexInSheet=-1|OwnerPartId=-1|Color=8388608|FontID=1|Text=2D|Name=Available Preview Images
|RECORD=1|LibReference=CAP|ComponentDescription=C0603X104K5RACAUTO|PartCount=2|DisplayModeCount=2|IndexInSheet=164|OwnerPartId=-1|Location.X=1350|Location.Y=390|Orientation=1|CurrentPartId=1|SourceLibraryName=Altium Content Vault|TargetFileName=*|AreaColor=11599871|Color=128|PartIDLocked=F|DesignItemId=CMP-2006-00003-1|AllPinCount=2
|RECORD=2|OwnerIndex=1508|OwnerPartId=1|OwnerPartDisplayMode=1|FormalType=1|Electrical=4|PinConglomerate=35|PinLength=10|Location.X=1360|Location.Y=390|Name=1|Designator=1|PinPropagationDelay=0.000000E+000
|RECORD=2|OwnerIndex=1508|OwnerPartId=1|OwnerPartDisplayMode=1|FormalType=1|Electrical=4|PinConglomerate=33|PinLength=10|Location.X=1360|Location.Y=400|Name=2|Designator=2|PinPropagationDelay=0.000000E+000
|RECORD=13|OwnerIndex=1508|IsNotAccesible=T|IndexInSheet=2|OwnerPartId=1|OwnerPartDisplayMode=1|Location.X=1368|Location.Y=390|Corner.X=1352|Corner.Y=390|LineWidth=1|Color=16711680
|RECORD=13|OwnerIndex=1508|IsNotAccesible=T|IndexInSheet=3|OwnerPartId=1|OwnerPartDisplayMode=1|Location.X=1360|Location.Y=394|Corner.X=1360|Corner.Y=400|LineWidth=1|Color=16711680
|RECORD=12|OwnerIndex=1508|IsNotAccesible=T|IndexInSheet=4|OwnerPartId=1|OwnerPartDisplayMode=1|Location.X=1360|Location.Y=410|Radius=16|LineWidth=1|StartAngle=241.000|EndAngle=270.000|Color=16711680
|RECORD=12|OwnerIndex=1508|IsNotAccesible=T|IndexInSheet=5|OwnerPartId=1|OwnerPartDisplayMode=1|Location.X=1360|Location.Y=410|Radius=16|LineWidth=1|StartAngle=270.000|EndAngle=299.000|Color=16711680
|RECORD=2|OwnerIndex=1508|OwnerPartId=1|FormalType=1|Electrical=4|PinConglomerate=35|PinLength=10|Location.X=1360|Location.Y=390|Name=1|Designator=1|PinPropagationDelay=0.000000E+000
|RECORD=2|OwnerIndex=1508|OwnerPartId=1|FormalType=1|Electrical=4|PinConglomerate=33|PinLength=10|Location.X=1360|Location.Y=400|Name=2|Designator=2|PinPropagationDelay=0.000000E+000
|RECORD=13|OwnerIndex=1508|IsNotAccesible=T|IndexInSheet=8|OwnerPartId=1|Location.X=1352|Location.Y=397|Corner.X=1368|Corner.Y=397|LineWidth=1|Color=16711680
|RECORD=13|OwnerIndex=1508|IsNotAccesible=T|IndexInSheet=9|OwnerPartId=1|Location.X=1368|Location.Y=393|Corner.X=1352|Corner.Y=393|LineWidth=1|Color=16711680
|RECORD=6|OwnerIndex=1508|IsNotAccesible=T|IndexInSheet=10|OwnerPartId=1|LineWidth=1|Color=16711680|LocationCount=2|X1=1360|Y1=390|X2=1360|Y2=393
|RECORD=6|OwnerIndex=1508|IsNotAccesible=T|IndexInSheet=11|OwnerPartId=1|LineWidth=1|Color=16711680|LocationCount=2|X1=1360|Y1=400|X2=1360|Y2=397
|RECORD=41|OwnerIndex=1508|IndexInSheet=12|OwnerPartId=-1|Location.X=1351|Location.Y=412|Color=8388608|FontID=1|IsHidden=T|Text=Kemet|Name=Manufacturer
|RECORD=41|OwnerIndex=1508|IndexInSheet=13|OwnerPartId=-1|Location.X=1351|Location.Y=412|Color=8388608|FontID=1|IsHidden=T|Text=C0603X104K5RACAUTO|Name=Part Number
|RECORD=34|OwnerIndex=1508|IndexInSheet=-1|OwnerPartId=-1|Location.X=1369|Location.Y=391|Color=8388608|FontID=3|Text=C9|Name=Designator|ReadOnlyState=1
|RECORD=41|OwnerIndex=1508|IndexInSheet=-1|OwnerPartId=-1|Location.X=1370|Location.Y=380|Color=8388608|FontID=3|Text=0.1uF|Name=Comment
|RECORD=44|OwnerIndex=1508
|RECORD=45|OwnerIndex=1529|IndexInSheet=-1|Description=Chip Capacitor, 2-Leads, Body 1.60x0.80mm, IPC Low Density|UseComponentLibrary=T|ModelName=CAPC1608X87X45ML20T05|ModelType=PCBLIB|DatafileCount=1|ModelDatafileEntity0=CAPC1608X87X45ML20T05|ModelDatafileKind0=PCBLib|IsCurrent=T|DatalinksLocked=T|DatabaseDatalinksLocked=T
|RECORD=46|OwnerIndex=1530
|RECORD=48|OwnerIndex=1530
|RECORD=41|OwnerIndex=1532|IndexInSheet=-1|OwnerPartId=-1|Color=8388608|FontID=1|Text=2D|Name=Available Preview Images
|RECORD=45|OwnerIndex=1529|IndexInSheet=-1|Description=Chip Capacitor, 2-Leads, Body 1.60x0.80mm, IPC High Density|UseComponentLibrary=T|ModelName=CAPC1608X87X45LL20T05|ModelType=PCBLIB|DatafileCount=1|ModelDatafileEntity0=CAPC1608X87X45LL20T05|ModelDatafileKind0=PCBLib|DatalinksLocked=T|DatabaseDatalinksLocked=T
|RECORD=46|OwnerIndex=1534
|RECORD=48|OwnerIndex=1534
|RECORD=41|OwnerIndex=1536|IndexInSheet=-1|OwnerPartId=-1|Color=8388608|FontID=1|Text=2D|Name=Available Preview Images
|RECORD=45|OwnerIndex=1529|IndexInSheet=-1|Description=Chip Capacitor, 2-Leads, Body 1.60x0.80mm, IPC Medium Density|UseComponentLibrary=T|ModelName=CAPC1608X87X45NL20T05|ModelType=PCBLIB|DatafileCount=1|ModelDatafileEntity0=CAPC1608X87X45NL20T05|ModelDatafileKind0=PCBLib|DatalinksLocked=T|DatabaseDatalinksLocked=T
|RECORD=46|OwnerIndex=1538
|RECORD=48|OwnerIndex=1538
|RECORD=41|OwnerIndex=1540|IndexInSheet=-1|OwnerPartId=-1|Color=8388608|FontID=1|Text=2D|Name=Available Preview Images
|RECORD=1|LibReference=CAP|ComponentDescription=C0603X104K5RACAUTO|PartCount=2|DisplayModeCount=2|IndexInSheet=165|OwnerPartId=-1|Location.X=1400|Location.Y=390|Orientation=1|CurrentPartId=1|SourceLibraryName=Altium Content Vault|TargetFileName=*|AreaColor=11599871|Color=128|PartIDLocked=F|DesignItemId=CMP-2006-00003-1|AllPinCount=2
|RECORD=2|OwnerIndex=1542|OwnerPartId=1|OwnerPartDisplayMode=1|FormalType=1|Electrical=4|PinConglomerate=35|PinLength=10|Location.X=1410|Location.Y=390|Name=1|Designator=1|PinPropagationDelay=0.000000E+000
|RECORD=2|OwnerIndex=1542|OwnerPartId=1|OwnerPartDisplayMode=1|FormalType=1|Electrical=4|PinConglomerate=33|PinLength=10|Location.X=1410|Location.Y=400|Name=2|Designator=2|PinPropagationDelay=0.000000E+000
|RECORD=13|OwnerIndex=1542|IsNotAccesible=T|IndexInSheet=2|OwnerPartId=1|OwnerPartDisplayMode=1|Location.X=1418|Location.Y=390|Corner.X=1402|Corner.Y=390|LineWidth=1|Color=16711680
|RECORD=13|OwnerIndex=1542|IsNotAccesible=T|IndexInSheet=3|OwnerPartId=1|OwnerPartDisplayMode=1|Location.X=1410|Location.Y=394|Corner.X=1410|Corner.Y=400|LineWidth=1|Color=16711680
|RECORD=12|OwnerIndex=1542|IsNotAccesible=T|IndexInSheet=4|OwnerPartId=1|OwnerPartDisplayMode=1|Location.X=1410|Location.Y=410|Radius=16|LineWidth=1|StartAngle=241.000|EndAngle=270.000|Color=16711680
|RECORD=12|OwnerIndex=1542|IsNotAccesible=T|IndexInSheet=5|OwnerPartId=1|OwnerPartDisplayMode=1|Location.X=1410|Location.Y=410|Radius=16|LineWidth=1|StartAngle=270.000|EndAngle=299.000|Color=16711680
|RECORD=2|OwnerIndex=1542|OwnerPartId=1|FormalType=1|Electrical=4|PinConglomerate=35|PinLength=10|Location.X=1410|Location.Y=390|Name=1|Designator=1|PinPropagationDelay=0.000000E+000
|RECORD=2|OwnerIndex=1542|OwnerPartId=1|FormalType=1|Electrical=4|PinConglomerate=33|PinLength=10|Location.X=1410|Location.Y=400|Name=2|Designator=2|PinPropagationDelay=0.000000E+000
|RECORD=13|OwnerIndex=1542|IsNotAccesible=T|IndexInSheet=8|OwnerPartId=1|Location.X=1402|Location.Y=397|Corner.X=1418|Corner.Y=397|LineWidth=1|Color=16711680
|RECORD=13|OwnerIndex=1542|IsNotAccesible=T|IndexInSheet=9|OwnerPartId=1|Location.X=1418|Location.Y=393|Corner.X=1402|Corner.Y=393|LineWidth=1|Color=16711680
|RECORD=6|OwnerIndex=1542|IsNotAccesible=T|IndexInSheet=10|OwnerPartId=1|LineWidth=1|Color=16711680|LocationCount=2|X1=1410|Y1=390|X2=1410|Y2=393
|RECORD=6|OwnerIndex=1542|IsNotAccesible=T|IndexInSheet=11|OwnerPartId=1|LineWidth=1|Color=16711680|LocationCount=2|X1=1410|Y1=400|X2=1410|Y2=397
|RECORD=41|OwnerIndex=1542|IndexInSheet=12|OwnerPartId=-1|Location.X=1401|Location.Y=412|Color=8388608|FontID=1|IsHidden=T|Text=Kemet|Name=Manufacturer
|RECORD=41|OwnerIndex=1542|IndexInSheet=13|OwnerPartId=-1|Location.X=1401|Location.Y=412|Color=8388608|FontID=1|IsHidden=T|Text=C0603X104K5RACAUTO|Name=Part Number
|RECORD=34|OwnerIndex=1542|IndexInSheet=-1|OwnerPartId=-1|Location.X=1419|Location.Y=391|Color=8388608|FontID=3|Text=C10|Name=Designator|ReadOnlyState=1
|RECORD=41|OwnerIndex=1542|IndexInSheet=-1|OwnerPartId=-1|Location.X=1419|Location.Y=381|Color=8388608|FontID=3|Text=0.1uF|Name=Comment
|RECORD=44|OwnerIndex=1542
|RECORD=45|OwnerIndex=1563|IndexInSheet=-1|Description=Chip Capacitor, 2-Leads, Body 1.60x0.80mm, IPC Low Density|UseComponentLibrary=T|ModelName=CAPC1608X87X45ML20T05|ModelType=PCBLIB|DatafileCount=1|ModelDatafileEntity0=CAPC1608X87X45ML20T05|ModelDatafileKind0=PCBLib|IsCurrent=T|DatalinksLocked=T|DatabaseDatalinksLocked=T
|RECORD=46|OwnerIndex=1564
|RECORD=48|OwnerIndex=1564
|RECORD=41|OwnerIndex=1566|IndexInSheet=-1|OwnerPartId=-1|Color=8388608|FontID=1|Text=2D|Name=Available Preview Images
|RECORD=45|OwnerIndex=1563|IndexInSheet=-1|Description=Chip Capacitor, 2-Leads, Body 1.60x0.80mm, IPC High Density|UseComponentLibrary=T|ModelName=CAPC1608X87X45LL20T05|ModelType=PCBLIB|DatafileCount=1|ModelDatafileEntity0=CAPC1608X87X45LL20T05|ModelDatafileKind0=PCBLib|DatalinksLocked=T|DatabaseDatalinksLocked=T
|RECORD=46|OwnerIndex=1568
|RECORD=48|OwnerIndex=1568
|RECORD=41|OwnerIndex=1570|IndexInSheet=-1|OwnerPartId=-1|Color=8388608|FontID=1|Text=2D|Name=Available Preview Images
|RECORD=45|OwnerIndex=1563|IndexInSheet=-1|Description=Chip Capacitor, 2-Leads, Body 1.60x0.80mm, IPC Medium Density|UseComponentLibrary=T|ModelName=CAPC1608X87X45NL20T05|ModelType=PCBLIB|DatafileCount=1|ModelDatafileEntity0=CAPC1608X87X45NL20T05|ModelDatafileKind0=PCBLib|DatalinksLocked=T|DatabaseDatalinksLocked=T
|RECORD=46|OwnerIndex=1572
|RECORD=48|OwnerIndex=1572
|RECORD=41|OwnerIndex=1574|IndexInSheet=-1|OwnerPartId=-1|Color=8388608|FontID=1|Text=2D|Name=Available Preview Images
|RECORD=1|LibReference=CAP|ComponentDescription=C0603X104K5RACAUTO|PartCount=2|DisplayModeCount=2|IndexInSheet=166|OwnerPartId=-1|Location.X=1450|Location.Y=390|Orientation=1|CurrentPartId=1|SourceLibraryName=Altium Content Vault|TargetFileName=*|AreaColor=11599871|Color=128|PartIDLocked=F|DesignItemId=CMP-2006-00003-1|AllPinCount=2
|RECORD=2|OwnerIndex=1576|OwnerPartId=1|OwnerPartDisplayMode=1|FormalType=1|Electrical=4|PinConglomerate=35|PinLength=10|Location.X=1460|Location.Y=390|Name=1|Designator=1|PinPropagationDelay=0.000000E+000
|RECORD=2|OwnerIndex=1576|OwnerPartId=1|OwnerPartDisplayMode=1|FormalType=1|Electrical=4|PinConglomerate=33|PinLength=10|Location.X=1460|Location.Y=400|Name=2|Designator=2|PinPropagationDelay=0.000000E+000
|RECORD=13|OwnerIndex=1576|IsNotAccesible=T|IndexInSheet=2|OwnerPartId=1|OwnerPartDisplayMode=1|Location.X=1468|Location.Y=390|Corner.X=1452|Corner.Y=390|LineWidth=1|Color=16711680
|RECORD=13|OwnerIndex=1576|IsNotAccesible=T|IndexInSheet=3|OwnerPartId=1|OwnerPartDisplayMode=1|Location.X=1460|Location.Y=394|Corner.X=1460|Corner.Y=400|LineWidth=1|Color=16711680
|RECORD=12|OwnerIndex=1576|IsNotAccesible=T|IndexInSheet=4|OwnerPartId=1|OwnerPartDisplayMode=1|Location.X=1460|Location.Y=410|Radius=16|LineWidth=1|StartAngle=241.000|EndAngle=270.000|Color=16711680
|RECORD=12|OwnerIndex=1576|IsNotAccesible=T|IndexInSheet=5|OwnerPartId=1|OwnerPartDisplayMode=1|Location.X=1460|Location.Y=410|Radius=16|LineWidth=1|StartAngle=270.000|EndAngle=299.000|Color=16711680
|RECORD=2|OwnerIndex=1576|OwnerPartId=1|FormalType=1|Electrical=4|PinConglomerate=35|PinLength=10|Location.X=1460|Location.Y=390|Name=1|Designator=1|PinPropagationDelay=0.000000E+000
|RECORD=2|OwnerIndex=1576|OwnerPartId=1|FormalType=1|Electrical=4|PinConglomerate=33|PinLength=10|Location.X=1460|Location.Y=400|Name=2|Designator=2|PinPropagationDelay=0.000000E+000
|RECORD=13|OwnerIndex=1576|IsNotAccesible=T|IndexInSheet=8|OwnerPartId=1|Location.X=1452|Location.Y=397|Corner.X=1468|Corner.Y=397|LineWidth=1|Color=16711680
|RECORD=13|OwnerIndex=1576|IsNotAccesible=T|IndexInSheet=9|OwnerPartId=1|Location.X=1468|Location.Y=393|Corner.X=1452|Corner.Y=393|LineWidth=1|Color=16711680
|RECORD=6|OwnerIndex=1576|IsNotAccesible=T|IndexInSheet=10|OwnerPartId=1|LineWidth=1|Color=16711680|LocationCount=2|X1=1460|Y1=390|X2=1460|Y2=393
|RECORD=6|OwnerIndex=1576|IsNotAccesible=T|IndexInSheet=11|OwnerPartId=1|LineWidth=1|Color=16711680|LocationCount=2|X1=1460|Y1=400|X2=1460|Y2=397
|RECORD=41|OwnerIndex=1576|IndexInSheet=12|OwnerPartId=-1|Location.X=1451|Location.Y=412|Color=8388608|FontID=1|IsHidden=T|Text=Kemet|Name=Manufacturer
|RECORD=41|OwnerIndex=1576|IndexInSheet=13|OwnerPartId=-1|Location.X=1451|Location.Y=412|Color=8388608|FontID=1|IsHidden=T|Text=C0603X104K5RACAUTO|Name=Part Number
|RECORD=34|OwnerIndex=1576|IndexInSheet=-1|OwnerPartId=-1|Location.X=1469|Location.Y=391|Color=8388608|FontID=3|Text=C11|Name=Designator|ReadOnlyState=1
|RECORD=41|OwnerIndex=1576|IndexInSheet=-1|OwnerPartId=-1|Location.X=1469|Location.Y=381|Color=8388608|FontID=3|Text=0.1uF|Name=Comment
|RECORD=44|OwnerIndex=1576
|RECORD=45|OwnerIndex=1597|IndexInSheet=-1|Description=Chip Capacitor, 2-Leads, Body 1.60x0.80mm, IPC Low Density|UseComponentLibrary=T|ModelName=CAPC1608X87X45ML20T05|ModelType=PCBLIB|DatafileCount=1|ModelDatafileEntity0=CAPC1608X87X45ML20T05|ModelDatafileKind0=PCBLib|IsCurrent=T|DatalinksLocked=T|DatabaseDatalinksLocked=T
|RECORD=46|OwnerIndex=1598
|RECORD=48|OwnerIndex=1598
|RECORD=41|OwnerIndex=1600|IndexInSheet=-1|OwnerPartId=-1|Color=8388608|FontID=1|Text=2D|Name=Available Preview Images
|RECORD=45|OwnerIndex=1597|IndexInSheet=-1|Description=Chip Capacitor, 2-Leads, Body 1.60x0.80mm, IPC High Density|UseComponentLibrary=T|ModelName=CAPC1608X87X45LL20T05|ModelType=PCBLIB|DatafileCount=1|ModelDatafileEntity0=CAPC1608X87X45LL20T05|ModelDatafileKind0=PCBLib|DatalinksLocked=T|DatabaseDatalinksLocked=T
|RECORD=46|OwnerIndex=1602
|RECORD=48|OwnerIndex=1602
|RECORD=41|OwnerIndex=1604|IndexInSheet=-1|OwnerPartId=-1|Color=8388608|FontID=1|Text=2D|Name=Available Preview Images
|RECORD=45|OwnerIndex=1597|IndexInSheet=-1|Description=Chip Capacitor, 2-Leads, Body 1.60x0.80mm, IPC Medium Density|UseComponentLibrary=T|ModelName=CAPC1608X87X45NL20T05|ModelType=PCBLIB|DatafileCount=1|ModelDatafileEntity0=CAPC1608X87X45NL20T05|ModelDatafileKind0=PCBLib|DatalinksLocked=T|DatabaseDatalinksLocked=T
|RECORD=46|OwnerIndex=1606
|RECORD=48|OwnerIndex=1606
|RECORD=41|OwnerIndex=1608|IndexInSheet=-1|OwnerPartId=-1|Color=8388608|FontID=1|Text=2D|Name=Available Preview Images
|RECORD=1|LibReference=CAP|ComponentDescription=C0603X104K5RACAUTO|PartCount=2|DisplayModeCount=2|IndexInSheet=167|OwnerPartId=-1|Location.X=1500|Location.Y=390|Orientation=1|CurrentPartId=1|SourceLibraryName=Altium Content Vault|TargetFileName=*|AreaColor=11599871|Color=128|PartIDLocked=F|DesignItemId=CMP-2006-00003-1|AllPinCount=2
|RECORD=2|OwnerIndex=1610|OwnerPartId=1|OwnerPartDisplayMode=1|FormalType=1|Electrical=4|PinConglomerate=35|PinLength=10|Location.X=1510|Location.Y=390|Name=1|Designator=1|PinPropagationDelay=0.000000E+000
|RECORD=2|OwnerIndex=1610|OwnerPartId=1|OwnerPartDisplayMode=1|FormalType=1|Electrical=4|PinConglomerate=33|PinLength=10|Location.X=1510|Location.Y=400|Name=2|Designator=2|PinPropagationDelay=0.000000E+000
|RECORD=13|OwnerIndex=1610|IsNotAccesible=T|IndexInSheet=2|OwnerPartId=1|OwnerPartDisplayMode=1|Location.X=1518|Location.Y=390|Corner.X=1502|Corner.Y=390|LineWidth=1|Color=16711680
|RECORD=13|OwnerIndex=1610|IsNotAccesible=T|IndexInSheet=3|OwnerPartId=1|OwnerPartDisplayMode=1|Location.X=1510|Location.Y=394|Corner.X=1510|Corner.Y=400|LineWidth=1|Color=16711680
|RECORD=12|OwnerIndex=1610|IsNotAccesible=T|IndexInSheet=4|OwnerPartId=1|OwnerPartDisplayMode=1|Location.X=1510|Location.Y=410|Radius=16|LineWidth=1|StartAngle=241.000|EndAngle=270.000|Color=16711680
|RECORD=12|OwnerIndex=1610|IsNotAccesible=T|IndexInSheet=5|OwnerPartId=1|OwnerPartDisplayMode=1|Location.X=1510|Location.Y=410|Radius=16|LineWidth=1|StartAngle=270.000|EndAngle=299.000|Color=16711680
|RECORD=2|OwnerIndex=1610|OwnerPartId=1|FormalType=1|Electrical=4|PinConglomerate=35|PinLength=10|Location.X=1510|Location.Y=390|Name=1|Designator=1|PinPropagationDelay=0.000000E+000
|RECORD=2|OwnerIndex=1610|OwnerPartId=1|FormalType=1|Electrical=4|PinConglomerate=33|PinLength=10|Location.X=1510|Location.Y=400|Name=2|Designator=2|PinPropagationDelay=0.000000E+000
|RECORD=13|OwnerIndex=1610|IsNotAccesible=T|IndexInSheet=8|OwnerPartId=1|Location.X=1502|Location.Y=397|Corner.X=1518|Corner.Y=397|LineWidth=1|Color=16711680
|RECORD=13|OwnerIndex=1610|IsNotAccesible=T|IndexInSheet=9|OwnerPartId=1|Location.X=1518|Location.Y=393|Corner.X=1502|Corner.Y=393|LineWidth=1|Color=16711680
|RECORD=6|OwnerIndex=1610|IsNotAccesible=T|IndexInSheet=10|OwnerPartId=1|LineWidth=1|Color=16711680|LocationCount=2|X1=1510|Y1=390|X2=1510|Y2=393
|RECORD=6|OwnerIndex=1610|IsNotAccesible=T|IndexInSheet=11|OwnerPartId=1|LineWidth=1|Color=16711680|LocationCount=2|X1=1510|Y1=400|X2=1510|Y2=397
|RECORD=41|OwnerIndex=1610|IndexInSheet=12|OwnerPartId=-1|Location.X=1501|Location.Y=412|Color=8388608|FontID=1|IsHidden=T|Text=Kemet|Name=Manufacturer
|RECORD=41|OwnerIndex=1610|IndexInSheet=13|OwnerPartId=-1|Location.X=1501|Location.Y=412|Color=8388608|FontID=1|IsHidden=T|Text=C0603X104K5RACAUTO|Name=Part Number
|RECORD=34|OwnerIndex=1610|IndexInSheet=-1|OwnerPartId=-1|Location.X=1519|Location.Y=391|Color=8388608|FontID=3|Text=C12|Name=Designator|ReadOnlyState=1
|RECORD=41|OwnerIndex=1610|IndexInSheet=-1|OwnerPartId=-1|Location.X=1519|Location.Y=381|Color=8388608|FontID=3|Text=0.1uF|Name=Comment
|RECORD=44|OwnerIndex=1610
|RECORD=45|OwnerIndex=1631|IndexInSheet=-1|Description=Chip Capacitor, 2-Leads, Body 1.60x0.80mm, IPC Low Density|UseComponentLibrary=T|ModelName=CAPC1608X87X45ML20T05|ModelType=PCBLIB|DatafileCount=1|ModelDatafileEntity0=CAPC1608X87X45ML20T05|ModelDatafileKind0=PCBLib|IsCurrent=T|DatalinksLocked=T|DatabaseDatalinksLocked=T
|RECORD=46|OwnerIndex=1632
|RECORD=48|OwnerIndex=1632
|RECORD=41|OwnerIndex=1634|IndexInSheet=-1|OwnerPartId=-1|Color=8388608|FontID=1|Text=2D|Name=Available Preview Images
|RECORD=45|OwnerIndex=1631|IndexInSheet=-1|Description=Chip Capacitor, 2-Leads, Body 1.60x0.80mm, IPC High Density|UseComponentLibrary=T|ModelName=CAPC1608X87X45LL20T05|ModelType=PCBLIB|DatafileCount=1|ModelDatafileEntity0=CAPC1608X87X45LL20T05|ModelDatafileKind0=PCBLib|DatalinksLocked=T|DatabaseDatalinksLocked=T
|RECORD=46|OwnerIndex=1636
|RECORD=48|OwnerIndex=1636
|RECORD=41|OwnerIndex=1638|IndexInSheet=-1|OwnerPartId=-1|Color=8388608|FontID=1|Text=2D|Name=Available Preview Images
|RECORD=45|OwnerIndex=1631|IndexInSheet=-1|Description=Chip Capacitor, 2-Leads, Body 1.60x0.80mm, IPC Medium Density|UseComponentLibrary=T|ModelName=CAPC1608X87X45NL20T05|ModelType=PCBLIB|DatafileCount=1|ModelDatafileEntity0=CAPC1608X87X45NL20T05|ModelDatafileKind0=PCBLib|DatalinksLocked=T|DatabaseDatalinksLocked=T
|RECORD=46|OwnerIndex=1640
|RECORD=48|OwnerIndex=1640
|RECORD=41|OwnerIndex=1642|IndexInSheet=-1|OwnerPartId=-1|Color=8388608|FontID=1|Text=2D|Name=Available Preview Images
|RECORD=1|LibReference=CAP|ComponentDescription=GCM188R71H333KA55D|PartCount=2|DisplayModeCount=2|IndexInSheet=168|OwnerPartId=-1|Location.X=1000|Location.Y=310|Orientation=1|CurrentPartId=1|SourceLibraryName=Altium Content Vault|TargetFileName=*|AreaColor=11599871|Color=128|PartIDLocked=F|DesignItemId=CMP-2006-02385-1|AllPinCount=2
|RECORD=2|OwnerIndex=1644|OwnerPartId=1|OwnerPartDisplayMode=1|FormalType=1|Electrical=4|PinConglomerate=35|PinLength=10|Location.X=1010|Location.Y=310|Name=1|Designator=1|PinPropagationDelay=0.000000E+000
|RECORD=2|OwnerIndex=1644|OwnerPartId=1|OwnerPartDisplayMode=1|FormalType=1|Electrical=4|PinConglomerate=33|PinLength=10|Location.X=1010|Location.Y=320|Name=2|Designator=2|PinPropagationDelay=0.000000E+000
|RECORD=13|OwnerIndex=1644|IsNotAccesible=T|IndexInSheet=2|OwnerPartId=1|OwnerPartDisplayMode=1|Location.X=1018|Location.Y=310|Corner.X=1002|Corner.Y=310|LineWidth=1|Color=16711680
|RECORD=13|OwnerIndex=1644|IsNotAccesible=T|IndexInSheet=3|OwnerPartId=1|OwnerPartDisplayMode=1|Location.X=1010|Location.Y=314|Corner.X=1010|Corner.Y=320|LineWidth=1|Color=16711680
|RECORD=12|OwnerIndex=1644|IsNotAccesible=T|IndexInSheet=4|OwnerPartId=1|OwnerPartDisplayMode=1|Location.X=1010|Location.Y=330|Radius=16|LineWidth=1|StartAngle=241.000|EndAngle=270.000|Color=16711680
|RECORD=12|OwnerIndex=1644|IsNotAccesible=T|IndexInSheet=5|OwnerPartId=1|OwnerPartDisplayMode=1|Location.X=1010|Location.Y=330|Radius=16|LineWidth=1|StartAngle=270.000|EndAngle=299.000|Color=16711680
|RECORD=2|OwnerIndex=1644|OwnerPartId=1|FormalType=1|Electrical=4|PinConglomerate=35|PinLength=10|Location.X=1010|Location.Y=310|Name=1|Designator=1|PinPropagationDelay=0.000000E+000
|RECORD=2|OwnerIndex=1644|OwnerPartId=1|FormalType=1|Electrical=4|PinConglomerate=33|PinLength=10|Location.X=1010|Location.Y=320|Name=2|Designator=2|PinPropagationDelay=0.000000E+000
|RECORD=13|OwnerIndex=1644|IsNotAccesible=T|IndexInSheet=8|OwnerPartId=1|Location.X=1002|Location.Y=317|Corner.X=1018|Corner.Y=317|LineWidth=1|Color=16711680
|RECORD=13|OwnerIndex=1644|IsNotAccesible=T|IndexInSheet=9|OwnerPartId=1|Location.X=1018|Location.Y=313|Corner.X=1002|Corner.Y=313|LineWidth=1|Color=16711680
|RECORD=6|OwnerIndex=1644|IsNotAccesible=T|IndexInSheet=10|OwnerPartId=1|LineWidth=1|Color=16711680|LocationCount=2|X1=1010|Y1=310|X2=1010|Y2=313
|RECORD=6|OwnerIndex=1644|IsNotAccesible=T|IndexInSheet=11|OwnerPartId=1|LineWidth=1|Color=16711680|LocationCount=2|X1=1010|Y1=320|X2=1010|Y2=317
|RECORD=41|OwnerIndex=1644|IndexInSheet=12|OwnerPartId=-1|Location.X=1001|Location.Y=332|Color=8388608|FontID=1|IsHidden=T|Text=Murata|Name=Manufacturer
|RECORD=41|OwnerIndex=1644|IndexInSheet=13|OwnerPartId=-1|Location.X=1001|Location.Y=332|Color=8388608|FontID=1|IsHidden=T|Text=GCM188R71H333KA55D|Name=Part Number
|RECORD=34|OwnerIndex=1644|IndexInSheet=-1|OwnerPartId=-1|Location.X=1019|Location.Y=311|Color=8388608|FontID=1|Text=C22|Name=Designator|ReadOnlyState=1
|RECORD=41|OwnerIndex=1644|IndexInSheet=-1|OwnerPartId=-1|Location.X=1019|Location.Y=301|Color=8388608|FontID=1|Text=0.033uF|Name=Comment
|RECORD=44|OwnerIndex=1644
|RECORD=45|OwnerIndex=1665|IndexInSheet=-1|Description=Chip Capacitor, 2-Leads, Body 1.60x0.80mm, IPC Medium Density|UseComponentLibrary=T|ModelName=CAPC1608X90X35NL10T15|ModelType=PCBLIB|DatafileCount=1|ModelDatafileEntity0=CAPC1608X90X35NL10T15|ModelDatafileKind0=PCBLib|IsCurrent=T|DatalinksLocked=T|DatabaseDatalinksLocked=T
|RECORD=46|OwnerIndex=1666
|RECORD=48|OwnerIndex=1666
|RECORD=41|OwnerIndex=1668|IndexInSheet=-1|OwnerPartId=-1|Color=8388608|FontID=1|Text=2D|Name=Available Preview Images
|RECORD=45|OwnerIndex=1665|IndexInSheet=-1|Description=Chip Capacitor, 2-Leads, Body 1.60x0.80mm, IPC Low Density|UseComponentLibrary=T|ModelName=CAPC1608X90X35ML10T15|ModelType=PCBLIB|DatafileCount=1|ModelDatafileEntity0=CAPC1608X90X35ML10T15|ModelDatafileKind0=PCBLib|DatalinksLocked=T|DatabaseDatalinksLocked=T
|RECORD=46|OwnerIndex=1670
|RECORD=48|OwnerIndex=1670
|RECORD=41|OwnerIndex=1672|IndexInSheet=-1|OwnerPartId=-1|Color=8388608|FontID=1|Text=2D|Name=Available Preview Images
|RECORD=45|OwnerIndex=1665|IndexInSheet=-1|Description=Chip Capacitor, 2-Leads, Body 1.60x0.80mm, IPC High Density|UseComponentLibrary=T|ModelName=CAPC1608X90X35LL10T15|ModelType=PCBLIB|DatafileCount=1|ModelDatafileEntity0=CAPC1608X90X35LL10T15|ModelDatafileKind0=PCBLib|DatalinksLocked=T|DatabaseDatalinksLocked=T
|RECORD=46|OwnerIndex=1674
|RECORD=48|OwnerIndex=1674
|RECORD=41|OwnerIndex=1676|IndexInSheet=-1|OwnerPartId=-1|Color=8388608|FontID=1|Text=2D|Name=Available Preview Images
|RECORD=1|LibReference=CAP|ComponentDescription=GCM188R71H333KA55D|PartCount=2|DisplayModeCount=2|IndexInSheet=169|OwnerPartId=-1|Location.X=250|Location.Y=340|Orientation=1|CurrentPartId=1|SourceLibraryName=Altium Content Vault|TargetFileName=*|AreaColor=11599871|Color=128|PartIDLocked=F|DesignItemId=CMP-2006-02385-1|AllPinCount=2
|RECORD=2|OwnerIndex=1678|OwnerPartId=1|OwnerPartDisplayMode=1|FormalType=1|Electrical=4|PinConglomerate=35|PinLength=10|Location.X=260|Location.Y=340|Name=1|Designator=1|PinPropagationDelay=0.000000E+000
|RECORD=2|OwnerIndex=1678|OwnerPartId=1|OwnerPartDisplayMode=1|FormalType=1|Electrical=4|PinConglomerate=33|PinLength=10|Location.X=260|Location.Y=350|Name=2|Designator=2|PinPropagationDelay=0.000000E+000
|RECORD=13|OwnerIndex=1678|IsNotAccesible=T|IndexInSheet=2|OwnerPartId=1|OwnerPartDisplayMode=1|Location.X=268|Location.Y=340|Corner.X=252|Corner.Y=340|LineWidth=1|Color=16711680
|RECORD=13|OwnerIndex=1678|IsNotAccesible=T|IndexInSheet=3|OwnerPartId=1|OwnerPartDisplayMode=1|Location.X=260|Location.Y=344|Corner.X=260|Corner.Y=350|LineWidth=1|Color=16711680
|RECORD=12|OwnerIndex=1678|IsNotAccesible=T|IndexInSheet=4|OwnerPartId=1|OwnerPartDisplayMode=1|Location.X=260|Location.Y=360|Radius=16|LineWidth=1|StartAngle=241.000|EndAngle=270.000|Color=16711680
|RECORD=12|OwnerIndex=1678|IsNotAccesible=T|IndexInSheet=5|OwnerPartId=1|OwnerPartDisplayMode=1|Location.X=260|Location.Y=360|Radius=16|LineWidth=1|StartAngle=270.000|EndAngle=299.000|Color=16711680
|RECORD=2|OwnerIndex=1678|OwnerPartId=1|FormalType=1|Electrical=4|PinConglomerate=35|PinLength=10|Location.X=260|Location.Y=340|Name=1|Designator=1|PinPropagationDelay=0.000000E+000
|RECORD=2|OwnerIndex=1678|OwnerPartId=1|FormalType=1|Electrical=4|PinConglomerate=33|PinLength=10|Location.X=260|Location.Y=350|Name=2|Designator=2|PinPropagationDelay=0.000000E+000
|RECORD=13|OwnerIndex=1678|IsNotAccesible=T|IndexInSheet=8|OwnerPartId=1|Location.X=252|Location.Y=347|Corner.X=268|Corner.Y=347|LineWidth=1|Color=16711680
|RECORD=13|OwnerIndex=1678|IsNotAccesible=T|IndexInSheet=9|OwnerPartId=1|Location.X=268|Location.Y=343|Corner.X=252|Corner.Y=343|LineWidth=1|Color=16711680
|RECORD=6|OwnerIndex=1678|IsNotAccesible=T|IndexInSheet=10|OwnerPartId=1|LineWidth=1|Color=16711680|LocationCount=2|X1=260|Y1=340|X2=260|Y2=343
|RECORD=6|OwnerIndex=1678|IsNotAccesible=T|IndexInSheet=11|OwnerPartId=1|LineWidth=1|Color=16711680|LocationCount=2|X1=260|Y1=350|X2=260|Y2=347
|RECORD=41|OwnerIndex=1678|IndexInSheet=12|OwnerPartId=-1|Location.X=251|Location.Y=362|Color=8388608|FontID=1|IsHidden=T|Text=Murata|Name=Manufacturer
|RECORD=41|OwnerIndex=1678|IndexInSheet=13|OwnerPartId=-1|Location.X=251|Location.Y=362|Color=8388608|FontID=1|IsHidden=T|Text=GCM188R71H333KA55D|Name=Part Number
|RECORD=34|OwnerIndex=1678|IndexInSheet=-1|OwnerPartId=-1|Location.X=269|Location.Y=341|Color=8388608|FontID=1|Text=C20|Name=Designator|ReadOnlyState=1
|RECORD=41|OwnerIndex=1678|IndexInSheet=-1|OwnerPartId=-1|Location.X=269|Location.Y=331|Color=8388608|FontID=1|Text=0.033uF|Name=Comment
|RECORD=44|OwnerIndex=1678
|RECORD=45|OwnerIndex=1699|IndexInSheet=-1|Description=Chip Capacitor, 2-Leads, Body 1.60x0.80mm, IPC Medium Density|UseComponentLibrary=T|ModelName=CAPC1608X90X35NL10T15|ModelType=PCBLIB|DatafileCount=1|ModelDatafileEntity0=CAPC1608X90X35NL10T15|ModelDatafileKind0=PCBLib|IsCurrent=T|DatalinksLocked=T|DatabaseDatalinksLocked=T
|RECORD=46|OwnerIndex=1700
|RECORD=48|OwnerIndex=1700
|RECORD=41|OwnerIndex=1702|IndexInSheet=-1|OwnerPartId=-1|Color=8388608|FontID=1|Text=2D|Name=Available Preview Images
|RECORD=45|OwnerIndex=1699|IndexInSheet=-1|Description=Chip Capacitor, 2-Leads, Body 1.60x0.80mm, IPC Low Density|UseComponentLibrary=T|ModelName=CAPC1608X90X35ML10T15|ModelType=PCBLIB|DatafileCount=1|ModelDatafileEntity0=CAPC1608X90X35ML10T15|ModelDatafileKind0=PCBLib|DatalinksLocked=T|DatabaseDatalinksLocked=T
|RECORD=46|OwnerIndex=1704
|RECORD=48|OwnerIndex=1704
|RECORD=41|OwnerIndex=1706|IndexInSheet=-1|OwnerPartId=-1|Color=8388608|FontID=1|Text=2D|Name=Available Preview Images
|RECORD=45|OwnerIndex=1699|IndexInSheet=-1|Description=Chip Capacitor, 2-Leads, Body 1.60x0.80mm, IPC High Density|UseComponentLibrary=T|ModelName=CAPC1608X90X35LL10T15|ModelType=PCBLIB|DatafileCount=1|ModelDatafileEntity0=CAPC1608X90X35LL10T15|ModelDatafileKind0=PCBLib|DatalinksLocked=T|DatabaseDatalinksLocked=T
|RECORD=46|OwnerIndex=1708
|RECORD=48|OwnerIndex=1708
|RECORD=41|OwnerIndex=1710|IndexInSheet=-1|OwnerPartId=-1|Color=8388608|FontID=1|Text=2D|Name=Available Preview Images
|RECORD=41|IndexInSheet=170|OwnerPartId=-1|Color=8388608|FontID=1|IsHidden=T|Name=ConfigurationParameters|ReadOnlyState=1
|RECORD=41|IndexInSheet=171|OwnerPartId=-1|Color=8388608|FontID=1|IsHidden=T|Name=ConfiguratorName|ReadOnlyState=1
|RECORD=41|IndexInSheet=172|OwnerPartId=-1|Color=8388608|FontID=1|IsHidden=T|Name=VersionControl_RevNumber|ReadOnlyState=1
|RECORD=41|IndexInSheet=173|OwnerPartId=-1|Color=8388608|FontID=1|IsHidden=T|Name=IsUserConfigurable|ReadOnlyState=1
|RECORD=41|IndexInSheet=174|OwnerPartId=-1|Color=8388608|FontID=1|IsHidden=T|Name=VersionControl_ProjFolderRevNumber|ReadOnlyState=1
|RECORD=41|IndexInSheet=175|OwnerPartId=-1|Color=8388608|FontID=1|IsHidden=T|Name=SPICEModelCache|ReadOnlyState=1
|RECORD=29|IndexInSheet=-1|OwnerPartId=-1|Location.X=50|Location.Y=550|Color=128
|RECORD=29|IndexInSheet=-1|OwnerPartId=-1|Location.X=100|Location.Y=320|Color=128
|RECORD=29|IndexInSheet=-1|OwnerPartId=-1|Location.X=110|Location.Y=550|Color=128
|RECORD=29|IndexInSheet=-1|OwnerPartId=-1|Location.X=210|Location.Y=320|Color=128
|RECORD=29|IndexInSheet=-1|OwnerPartId=-1|Location.X=210|Location.Y=790|Color=128
|RECORD=29|IndexInSheet=-1|OwnerPartId=-1|Location.X=210|Location.Y=800|Color=128
|RECORD=29|IndexInSheet=-1|OwnerPartId=-1|Location.X=210|Location.Y=830|Color=128
|RECORD=29|IndexInSheet=-1|OwnerPartId=-1|Location.X=210|Location.Y=840|Color=128
|RECORD=29|IndexInSheet=-1|OwnerPartId=-1|Location.X=210|Location.Y=930|Color=128
|RECORD=29|IndexInSheet=-1|OwnerPartId=-1|Location.X=370|Location.Y=460|Color=128
|RECORD=29|IndexInSheet=-1|OwnerPartId=-1|Location.X=380|Location.Y=320|Color=128
|RECORD=29|IndexInSheet=-1|OwnerPartId=-1|Location.X=380|Location.Y=430|Color=128
|RECORD=29|IndexInSheet=-1|OwnerPartId=-1|Location.X=450|Location.Y=430|Color=128
|RECORD=29|IndexInSheet=-1|OwnerPartId=-1|Location.X=450|Location.Y=460|Color=128
|RECORD=29|IndexInSheet=-1|OwnerPartId=-1|Location.X=490|Location.Y=840|Color=128
|RECORD=29|IndexInSheet=-1|OwnerPartId=-1|Location.X=490|Location.Y=950|Color=128
|RECORD=29|IndexInSheet=-1|OwnerPartId=-1|Location.X=500|Location.Y=320|Color=128
|RECORD=29|IndexInSheet=-1|OwnerPartId=-1|Location.X=500|Location.Y=430|Color=128
|RECORD=29|IndexInSheet=-1|OwnerPartId=-1|Location.X=550|Location.Y=320|Color=128
|RECORD=29|IndexInSheet=-1|OwnerPartId=-1|Location.X=550|Location.Y=430|Color=128
|RECORD=29|IndexInSheet=-1|OwnerPartId=-1|Location.X=600|Location.Y=320|Color=128
|RECORD=29|IndexInSheet=-1|OwnerPartId=-1|Location.X=600|Location.Y=430|Color=128
|RECORD=29|IndexInSheet=-1|OwnerPartId=-1|Location.X=630|Location.Y=970|Color=128
|RECORD=29|IndexInSheet=-1|OwnerPartId=-1|Location.X=650|Location.Y=320|Color=128
|RECORD=29|IndexInSheet=-1|OwnerPartId=-1|Location.X=650|Location.Y=430|Color=128
|RECORD=29|IndexInSheet=-1|OwnerPartId=-1|Location.X=680|Location.Y=890|Color=128
|RECORD=29|IndexInSheet=-1|OwnerPartId=-1|Location.X=680|Location.Y=970|Color=128
|RECORD=29|IndexInSheet=-1|OwnerPartId=-1|Location.X=700|Location.Y=320|Color=128
|RECORD=29|IndexInSheet=-1|OwnerPartId=-1|Location.X=700|Location.Y=430|Color=128
|RECORD=29|IndexInSheet=-1|OwnerPartId=-1|Location.X=820|Location.Y=280|Color=128
|RECORD=29|IndexInSheet=-1|OwnerPartId=-1|Location.X=820|Location.Y=560|Color=128
|RECORD=29|IndexInSheet=-1|OwnerPartId=-1|Location.X=880|Location.Y=280|Color=128
|RECORD=29|IndexInSheet=-1|OwnerPartId=-1|Location.X=880|Location.Y=560|Color=128
|RECORD=29|IndexInSheet=-1|OwnerPartId=-1|Location.X=960|Location.Y=280|Color=128
|RECORD=29|IndexInSheet=-1|OwnerPartId=-1|Location.X=1100|Location.Y=280|Color=128
|RECORD=29|IndexInSheet=-1|OwnerPartId=-1|Location.X=1100|Location.Y=430|Color=128
|RECORD=29|IndexInSheet=-1|OwnerPartId=-1|Location.X=1100|Location.Y=460|Color=128
|RECORD=29|IndexInSheet=-1|OwnerPartId=-1|Location.X=1260|Location.Y=280|Color=128
|RECORD=29|IndexInSheet=-1|OwnerPartId=-1|Location.X=1260|Location.Y=430|Color=128
|RECORD=29|IndexInSheet=-1|OwnerPartId=-1|Location.X=1260|Location.Y=460|Color=128
|RECORD=29|IndexInSheet=-1|OwnerPartId=-1|Location.X=1310|Location.Y=280|Color=128
|RECORD=29|IndexInSheet=-1|OwnerPartId=-1|Location.X=1310|Location.Y=430|Color=128
|RECORD=29|IndexInSheet=-1|OwnerPartId=-1|Location.X=1360|Location.Y=280|Color=128
|RECORD=29|IndexInSheet=-1|OwnerPartId=-1|Location.X=1360|Location.Y=430|Color=128
|RECORD=29|IndexInSheet=-1|OwnerPartId=-1|Location.X=1410|Location.Y=280|Color=128
|RECORD=29|IndexInSheet=-1|OwnerPartId=-1|Location.X=1410|Location.Y=430|Color=128
|RECORD=29|IndexInSheet=-1|OwnerPartId=-1|Location.X=1460|Location.Y=280|Color=128
|RECORD=29|IndexInSheet=-1|OwnerPartId=-1|Location.X=1460|Location.Y=430|Color=128